G04*
G04 #@! TF.GenerationSoftware,Altium Limited,Altium Designer,23.0.1 (38)*
G04*
G04 Layer_Color=2752767*
%FSLAX25Y25*%
%MOIN*%
G70*
G04*
G04 #@! TF.SameCoordinates,C48E81DB-6E20-4E2D-80E6-7C5AFAA1A21F*
G04*
G04*
G04 #@! TF.FilePolarity,Positive*
G04*
G01*
G75*
%ADD260C,0.00200*%
%ADD261C,0.00267*%
%ADD262C,0.00133*%
D260*
X695066Y-106410D02*
X695466D01*
X695866Y-106010D01*
X696266Y-106410D01*
X696666D01*
Y-106010D01*
X696266Y-105610D01*
X696666Y-105210D01*
Y-104810D01*
X696266D01*
X695866Y-105210D01*
X695466Y-104810D01*
X695066D01*
Y-105210D01*
X695466Y-105610D01*
X695066Y-106010D01*
Y-106410D01*
X695466Y-106010D02*
X695666D01*
X695866Y-105810D01*
X696066Y-106010D01*
X696266D01*
Y-105810D01*
X696066Y-105610D01*
X696266Y-105410D01*
Y-105210D01*
X696066D01*
X695866Y-105410D01*
X695666Y-105210D01*
X695466D01*
Y-105410D01*
X695666Y-105610D01*
X695466Y-105810D01*
Y-106010D01*
X695066Y-73142D02*
X695466D01*
X695866Y-72742D01*
X696266Y-73142D01*
X696666D01*
Y-72742D01*
X696266Y-72342D01*
X696666Y-71943D01*
Y-71543D01*
X696266D01*
X695866Y-71943D01*
X695466Y-71543D01*
X695066D01*
Y-71943D01*
X695466Y-72342D01*
X695066Y-72742D01*
Y-73142D01*
X695466Y-72742D02*
X695666D01*
X695866Y-72543D01*
X696066Y-72742D01*
X696266D01*
Y-72543D01*
X696066Y-72342D01*
X696266Y-72142D01*
Y-71943D01*
X696066D01*
X695866Y-72142D01*
X695666Y-71943D01*
X695466D01*
Y-72142D01*
X695666Y-72342D01*
X695466Y-72543D01*
Y-72742D01*
X688176Y-73142D02*
X688576D01*
X688976Y-72742D01*
X689376Y-73142D01*
X689776D01*
Y-72742D01*
X689376Y-72342D01*
X689776Y-71943D01*
Y-71543D01*
X689376D01*
X688976Y-71943D01*
X688576Y-71543D01*
X688176D01*
Y-71943D01*
X688576Y-72342D01*
X688176Y-72742D01*
Y-73142D01*
X688576Y-72742D02*
X688776D01*
X688976Y-72543D01*
X689176Y-72742D01*
X689376D01*
Y-72543D01*
X689176Y-72342D01*
X689376Y-72142D01*
Y-71943D01*
X689176D01*
X688976Y-72142D01*
X688776Y-71943D01*
X688576D01*
Y-72142D01*
X688776Y-72342D01*
X688576Y-72543D01*
Y-72742D01*
X688176Y-106410D02*
X688576D01*
X688976Y-106010D01*
X689376Y-106410D01*
X689776D01*
Y-106010D01*
X689376Y-105610D01*
X689776Y-105210D01*
Y-104810D01*
X689376D01*
X688976Y-105210D01*
X688576Y-104810D01*
X688176D01*
Y-105210D01*
X688576Y-105610D01*
X688176Y-106010D01*
Y-106410D01*
X688576Y-106010D02*
X688776D01*
X688976Y-105810D01*
X689176Y-106010D01*
X689376D01*
Y-105810D01*
X689176Y-105610D01*
X689376Y-105410D01*
Y-105210D01*
X689176D01*
X688976Y-105410D01*
X688776Y-105210D01*
X688576D01*
Y-105410D01*
X688776Y-105610D01*
X688576Y-105810D01*
Y-106010D01*
X683616Y-72804D02*
X682283D01*
Y-74803D01*
X683616D01*
X682283Y-73804D02*
X682950D01*
X683616Y-101150D02*
X682283D01*
Y-103150D01*
X683616D01*
X682283Y-102150D02*
X682950D01*
X643301Y-127845D02*
Y-128245D01*
X644101D01*
Y-127845D01*
X644501D01*
Y-127045D01*
X644101D01*
Y-126645D01*
X643301D01*
Y-127045D01*
X642901D01*
Y-127845D01*
X643301D01*
Y-144345D02*
Y-144745D01*
X644101D01*
Y-144345D01*
X644501D01*
Y-143545D01*
X644101D01*
Y-143145D01*
X643301D01*
Y-143545D01*
X642901D01*
Y-144345D01*
X643301D01*
X621601Y-127845D02*
Y-128245D01*
X622401D01*
Y-127845D01*
X622801D01*
Y-127045D01*
X622401D01*
Y-126645D01*
X621601D01*
Y-127045D01*
X621201D01*
Y-127845D01*
X621601D01*
Y-144345D02*
Y-144745D01*
X622401D01*
Y-144345D01*
X622801D01*
Y-143545D01*
X622401D01*
Y-143145D01*
X621601D01*
Y-143545D01*
X621201D01*
Y-144345D01*
X621601D01*
X639840Y-66006D02*
Y-64406D01*
X641440D01*
Y-66006D01*
X639840D01*
Y-18762D02*
Y-17162D01*
X641440D01*
Y-18762D01*
X639840D01*
X81985Y-23290D02*
Y-21690D01*
X83586D01*
Y-23290D01*
X81985D01*
Y-70534D02*
Y-68934D01*
X83586D01*
Y-70534D01*
X81985D01*
X180696Y-120879D02*
X181096Y-120079D01*
X180696Y-119279D01*
X181496Y-119679D01*
X182296Y-119279D01*
X181896Y-120079D01*
X182296Y-120879D01*
X181496Y-120479D01*
X180696Y-120879D01*
X170696D02*
X171096Y-120079D01*
X170696Y-119279D01*
X171496Y-119679D01*
X172296Y-119279D01*
X171896Y-120079D01*
X172296Y-120879D01*
X171496Y-120479D01*
X170696Y-120879D01*
X160696D02*
X161096Y-120079D01*
X160696Y-119279D01*
X161496Y-119679D01*
X162296Y-119279D01*
X161896Y-120079D01*
X162296Y-120879D01*
X161496Y-120479D01*
X160696Y-120879D01*
X150696D02*
X151096Y-120079D01*
X150696Y-119279D01*
X151496Y-119679D01*
X152296Y-119279D01*
X151896Y-120079D01*
X152296Y-120879D01*
X151496Y-120479D01*
X150696Y-120879D01*
X140696D02*
X141096Y-120079D01*
X140696Y-119279D01*
X141496Y-119679D01*
X142296Y-119279D01*
X141896Y-120079D01*
X142296Y-120879D01*
X141496Y-120479D01*
X140696Y-120879D01*
X270472Y-325166D02*
Y-327165D01*
X271472D01*
X271805Y-326832D01*
Y-325499D01*
X271472Y-325166D01*
X270472D01*
X282283D02*
Y-327165D01*
X283283D01*
X283616Y-326832D01*
Y-325499D01*
X283283Y-325166D01*
X282283D01*
X142520Y-154694D02*
Y-156693D01*
X143519D01*
X143853Y-156360D01*
Y-155027D01*
X143519Y-154694D01*
X142520D01*
X294094Y-325166D02*
Y-327165D01*
X295094D01*
X295427Y-326832D01*
Y-325499D01*
X295094Y-325166D01*
X294094D01*
X142520Y-314536D02*
Y-316535D01*
X143519D01*
X143853Y-316202D01*
Y-314869D01*
X143519Y-314536D01*
X142520D01*
X302362Y-154694D02*
Y-156693D01*
X303362D01*
X303695Y-156360D01*
Y-155027D01*
X303362Y-154694D01*
X302362D01*
X142520Y-234615D02*
Y-236614D01*
X143519D01*
X143853Y-236281D01*
Y-234948D01*
X143519Y-234615D01*
X142520D01*
X258472Y-325166D02*
Y-327165D01*
X259472D01*
X259805Y-326832D01*
Y-325499D01*
X259472Y-325166D01*
X258472D01*
X302362Y-314536D02*
Y-316535D01*
X303362D01*
X303695Y-316202D01*
Y-314869D01*
X303362Y-314536D01*
X302362D01*
X246472Y-325166D02*
Y-327165D01*
X247472D01*
X247805Y-326832D01*
Y-325499D01*
X247472Y-325166D01*
X246472D01*
X469475Y-309398D02*
X469875Y-308597D01*
X469475Y-307798D01*
X470275Y-308197D01*
X471075Y-307798D01*
X470675Y-308597D01*
X471075Y-309398D01*
X470275Y-308998D01*
X469475Y-309398D01*
X469875Y-308998D02*
X470075Y-308597D01*
X469875Y-308197D01*
X470275Y-308398D01*
X470675Y-308197D01*
X470475Y-308597D01*
X470675Y-308998D01*
X470275Y-308798D01*
X469875Y-308998D01*
X390735Y-309398D02*
X391135Y-308597D01*
X390735Y-307798D01*
X391535Y-308197D01*
X392335Y-307798D01*
X391935Y-308597D01*
X392335Y-309398D01*
X391535Y-308998D01*
X390735Y-309398D01*
X391135Y-308998D02*
X391335Y-308597D01*
X391135Y-308197D01*
X391535Y-308398D01*
X391935Y-308197D01*
X391735Y-308597D01*
X391935Y-308998D01*
X391535Y-308798D01*
X391135Y-308998D01*
X340104Y-274210D02*
X340504Y-273410D01*
X340104Y-272610D01*
X340904Y-273010D01*
X341704Y-272610D01*
X341304Y-273410D01*
X341704Y-274210D01*
X340904Y-273810D01*
X340104Y-274210D01*
X340504Y-273810D02*
X340704Y-273410D01*
X340504Y-273010D01*
X340904Y-273210D01*
X341304Y-273010D01*
X341104Y-273410D01*
X341304Y-273810D01*
X340904Y-273610D01*
X340504Y-273810D01*
X340104Y-195470D02*
X340504Y-194670D01*
X340104Y-193870D01*
X340904Y-194270D01*
X341704Y-193870D01*
X341304Y-194670D01*
X341704Y-195470D01*
X340904Y-195070D01*
X340104Y-195470D01*
X340504Y-195070D02*
X340704Y-194670D01*
X340504Y-194270D01*
X340904Y-194470D01*
X341304Y-194270D01*
X341104Y-194670D01*
X341304Y-195070D01*
X340904Y-194870D01*
X340504Y-195070D01*
X390744Y-161277D02*
X391144Y-160477D01*
X390744Y-159677D01*
X391545Y-160077D01*
X392344Y-159677D01*
X391945Y-160477D01*
X392344Y-161277D01*
X391545Y-160877D01*
X390744Y-161277D01*
X391144Y-160877D02*
X391344Y-160477D01*
X391144Y-160077D01*
X391545Y-160277D01*
X391945Y-160077D01*
X391744Y-160477D01*
X391945Y-160877D01*
X391545Y-160677D01*
X391144Y-160877D01*
X469485Y-161277D02*
X469885Y-160477D01*
X469485Y-159677D01*
X470285Y-160077D01*
X471085Y-159677D01*
X470685Y-160477D01*
X471085Y-161277D01*
X470285Y-160877D01*
X469485Y-161277D01*
X469885Y-160877D02*
X470085Y-160477D01*
X469885Y-160077D01*
X470285Y-160277D01*
X470685Y-160077D01*
X470485Y-160477D01*
X470685Y-160877D01*
X470285Y-160677D01*
X469885Y-160877D01*
X527595Y-195480D02*
X527995Y-194680D01*
X527595Y-193880D01*
X528395Y-194280D01*
X529195Y-193880D01*
X528795Y-194680D01*
X529195Y-195480D01*
X528395Y-195080D01*
X527595Y-195480D01*
X527995Y-195080D02*
X528195Y-194680D01*
X527995Y-194280D01*
X528395Y-194480D01*
X528795Y-194280D01*
X528595Y-194680D01*
X528795Y-195080D01*
X528395Y-194880D01*
X527995Y-195080D01*
X527595Y-274220D02*
X527995Y-273420D01*
X527595Y-272620D01*
X528395Y-273020D01*
X529195Y-272620D01*
X528795Y-273420D01*
X529195Y-274220D01*
X528395Y-273820D01*
X527595Y-274220D01*
X527995Y-273820D02*
X528195Y-273420D01*
X527995Y-273020D01*
X528395Y-273220D01*
X528795Y-273020D01*
X528595Y-273420D01*
X528795Y-273820D01*
X528395Y-273620D01*
X527995Y-273820D01*
X285128Y-306633D02*
Y-308632D01*
X286127D01*
X286461Y-308299D01*
Y-307966D01*
X286127Y-307633D01*
X285128D01*
X286127D01*
X286461Y-307299D01*
Y-306966D01*
X286127Y-306633D01*
X285128D01*
X160020Y-312536D02*
Y-314535D01*
X161019D01*
X161353Y-314202D01*
Y-313869D01*
X161019Y-313536D01*
X160020D01*
X161019D01*
X161353Y-313203D01*
Y-312869D01*
X161019Y-312536D01*
X160020D01*
X162520Y-150694D02*
Y-152693D01*
X163519D01*
X163853Y-152360D01*
Y-152026D01*
X163519Y-151693D01*
X162520D01*
X163519D01*
X163853Y-151360D01*
Y-151027D01*
X163519Y-150694D01*
X162520D01*
X284862Y-162794D02*
Y-164793D01*
X285862D01*
X286195Y-164460D01*
Y-164127D01*
X285862Y-163793D01*
X284862D01*
X285862D01*
X286195Y-163460D01*
Y-163127D01*
X285862Y-162794D01*
X284862D01*
X532615Y-313164D02*
Y-313564D01*
X533415D01*
Y-313164D01*
X533815D01*
Y-312364D01*
X533415D01*
Y-311964D01*
X532615D01*
Y-312364D01*
X532215D01*
Y-313164D01*
X532615D01*
X532815Y-312964D02*
Y-313164D01*
X533215D01*
Y-312964D01*
X533415D01*
Y-312564D01*
X533215D01*
Y-312364D01*
X532815D01*
Y-312564D01*
X532615D01*
Y-312964D01*
X532815D01*
X336015Y-156164D02*
Y-156564D01*
X336815D01*
Y-156164D01*
X337215D01*
Y-155364D01*
X336815D01*
Y-154964D01*
X336015D01*
Y-155364D01*
X335615D01*
Y-156164D01*
X336015D01*
X336215Y-155964D02*
Y-156164D01*
X336615D01*
Y-155964D01*
X336815D01*
Y-155564D01*
X336615D01*
Y-155364D01*
X336215D01*
Y-155564D01*
X336015D01*
Y-155964D01*
X336215D01*
X336115Y-313164D02*
Y-313564D01*
X336915D01*
Y-313164D01*
X337315D01*
Y-312364D01*
X336915D01*
Y-311964D01*
X336115D01*
Y-312364D01*
X335715D01*
Y-313164D01*
X336115D01*
X336315Y-312964D02*
Y-313164D01*
X336715D01*
Y-312964D01*
X336915D01*
Y-312564D01*
X336715D01*
Y-312364D01*
X336315D01*
Y-312564D01*
X336115D01*
Y-312964D01*
X336315D01*
X532615Y-156164D02*
Y-156564D01*
X533415D01*
Y-156164D01*
X533815D01*
Y-155364D01*
X533415D01*
Y-154964D01*
X532615D01*
Y-155364D01*
X532215D01*
Y-156164D01*
X532615D01*
X532815Y-155964D02*
Y-156164D01*
X533215D01*
Y-155964D01*
X533415D01*
Y-155564D01*
X533215D01*
Y-155364D01*
X532815D01*
Y-155564D01*
X532615D01*
Y-155964D01*
X532815D01*
X604291Y-330839D02*
X603491Y-329239D01*
X605091D01*
X604291Y-330839D01*
X574291D02*
X573491Y-329239D01*
X575091D01*
X574291Y-330839D01*
X-18464Y-327581D02*
X-19264Y-325981D01*
X-17664D01*
X-18464Y-327581D01*
Y-327181D02*
X-18865Y-326381D01*
X-18065D01*
X-18464Y-327181D01*
X-8465Y-317581D02*
X-8065Y-317181D01*
X-7665D01*
X-8065Y-316781D01*
X-7665Y-316381D01*
X-8065D01*
X-8465Y-315981D01*
X-8864Y-316381D01*
X-9264D01*
X-8864Y-316781D01*
X-9264Y-317181D01*
X-8864D01*
X-8465Y-317581D01*
Y-317181D02*
X-8264Y-316981D01*
X-8065D01*
X-8264Y-316781D01*
X-8065Y-316581D01*
X-8264D01*
X-8465Y-316381D01*
X-8664Y-316581D01*
X-8864D01*
X-8664Y-316781D01*
X-8864Y-316981D01*
X-8664D01*
X-8465Y-317181D01*
X1535Y-327581D02*
X735Y-325981D01*
X2335D01*
X1535Y-327581D01*
Y-327181D02*
X1135Y-326381D01*
X1936D01*
X1535Y-327181D01*
Y-307581D02*
X735Y-305981D01*
X2335D01*
X1535Y-307581D01*
Y-307181D02*
X1135Y-306381D01*
X1936D01*
X1535Y-307181D01*
X-18464Y-307581D02*
X-19264Y-305981D01*
X-17664D01*
X-18464Y-307581D01*
Y-307181D02*
X-18865Y-306381D01*
X-18065D01*
X-18464Y-307181D01*
X-18465Y-274430D02*
X-19265Y-272830D01*
X-17665D01*
X-18465Y-274430D01*
Y-274030D02*
X-18865Y-273230D01*
X-18065D01*
X-18465Y-274030D01*
X-8465Y-264430D02*
X-8065Y-264030D01*
X-7665D01*
X-8065Y-263630D01*
X-7665Y-263230D01*
X-8065D01*
X-8465Y-262830D01*
X-8865Y-263230D01*
X-9265D01*
X-8865Y-263630D01*
X-9265Y-264030D01*
X-8865D01*
X-8465Y-264430D01*
Y-264030D02*
X-8265Y-263830D01*
X-8065D01*
X-8265Y-263630D01*
X-8065Y-263430D01*
X-8265D01*
X-8465Y-263230D01*
X-8665Y-263430D01*
X-8865D01*
X-8665Y-263630D01*
X-8865Y-263830D01*
X-8665D01*
X-8465Y-264030D01*
X1535Y-274430D02*
X735Y-272830D01*
X2335D01*
X1535Y-274430D01*
Y-274030D02*
X1135Y-273230D01*
X1935D01*
X1535Y-274030D01*
Y-254430D02*
X735Y-252830D01*
X2335D01*
X1535Y-254430D01*
Y-254030D02*
X1135Y-253230D01*
X1935D01*
X1535Y-254030D01*
X-18465Y-254430D02*
X-19265Y-252830D01*
X-17665D01*
X-18465Y-254430D01*
Y-254030D02*
X-18865Y-253230D01*
X-18065D01*
X-18465Y-254030D01*
Y-221280D02*
X-19265Y-219680D01*
X-17665D01*
X-18465Y-221280D01*
Y-220880D02*
X-18865Y-220080D01*
X-18065D01*
X-18465Y-220880D01*
X-8465Y-211280D02*
X-8065Y-210880D01*
X-7665D01*
X-8065Y-210480D01*
X-7665Y-210080D01*
X-8065D01*
X-8465Y-209680D01*
X-8865Y-210080D01*
X-9265D01*
X-8865Y-210480D01*
X-9265Y-210880D01*
X-8865D01*
X-8465Y-211280D01*
Y-210880D02*
X-8265Y-210680D01*
X-8065D01*
X-8265Y-210480D01*
X-8065Y-210280D01*
X-8265D01*
X-8465Y-210080D01*
X-8665Y-210280D01*
X-8865D01*
X-8665Y-210480D01*
X-8865Y-210680D01*
X-8665D01*
X-8465Y-210880D01*
X1535Y-221280D02*
X735Y-219680D01*
X2335D01*
X1535Y-221280D01*
Y-220880D02*
X1135Y-220080D01*
X1935D01*
X1535Y-220880D01*
Y-201280D02*
X735Y-199680D01*
X2335D01*
X1535Y-201280D01*
Y-200880D02*
X1135Y-200080D01*
X1935D01*
X1535Y-200880D01*
X-18465Y-201280D02*
X-19265Y-199680D01*
X-17665D01*
X-18465Y-201280D01*
Y-200880D02*
X-18865Y-200080D01*
X-18065D01*
X-18465Y-200880D01*
X-18464Y-168132D02*
X-19264Y-166532D01*
X-17664D01*
X-18464Y-168132D01*
Y-167732D02*
X-18865Y-166932D01*
X-18065D01*
X-18464Y-167732D01*
X-8465Y-158132D02*
X-8065Y-157732D01*
X-7665D01*
X-8065Y-157332D01*
X-7665Y-156932D01*
X-8065D01*
X-8465Y-156532D01*
X-8864Y-156932D01*
X-9264D01*
X-8864Y-157332D01*
X-9264Y-157732D01*
X-8864D01*
X-8465Y-158132D01*
Y-157732D02*
X-8264Y-157532D01*
X-8065D01*
X-8264Y-157332D01*
X-8065Y-157132D01*
X-8264D01*
X-8465Y-156932D01*
X-8664Y-157132D01*
X-8864D01*
X-8664Y-157332D01*
X-8864Y-157532D01*
X-8664D01*
X-8465Y-157732D01*
X1535Y-168132D02*
X735Y-166532D01*
X2335D01*
X1535Y-168132D01*
Y-167732D02*
X1135Y-166932D01*
X1936D01*
X1535Y-167732D01*
Y-148132D02*
X735Y-146532D01*
X2335D01*
X1535Y-148132D01*
Y-147732D02*
X1135Y-146932D01*
X1936D01*
X1535Y-147732D01*
X-18464Y-148132D02*
X-19264Y-146532D01*
X-17664D01*
X-18464Y-148132D01*
Y-147732D02*
X-18865Y-146932D01*
X-18065D01*
X-18464Y-147732D01*
X639840Y-34510D02*
Y-32910D01*
X641440D01*
Y-34510D01*
X639840D01*
X81985Y-54786D02*
Y-53186D01*
X83586D01*
Y-54786D01*
X81985D01*
X588255Y13137D02*
X588655D01*
X589055Y13537D01*
X589455Y13137D01*
X589855D01*
Y13537D01*
X589455Y13937D01*
X589855Y14337D01*
Y14737D01*
X589455D01*
X589055Y14337D01*
X588655Y14737D01*
X588255D01*
Y14337D01*
X588655Y13937D01*
X588255Y13537D01*
Y13137D01*
X578255D02*
X578655D01*
X579055Y13537D01*
X579455Y13137D01*
X579855D01*
Y13537D01*
X579455Y13937D01*
X579855Y14337D01*
Y14737D01*
X579455D01*
X579055Y14337D01*
X578655Y14737D01*
X578255D01*
Y14337D01*
X578655Y13937D01*
X578255Y13537D01*
Y13137D01*
X568255D02*
X568655D01*
X569055Y13537D01*
X569455Y13137D01*
X569855D01*
Y13537D01*
X569455Y13937D01*
X569855Y14337D01*
Y14737D01*
X569455D01*
X569055Y14337D01*
X568655Y14737D01*
X568255D01*
Y14337D01*
X568655Y13937D01*
X568255Y13537D01*
Y13137D01*
X558255D02*
X558655D01*
X559055Y13537D01*
X559455Y13137D01*
X559855D01*
Y13537D01*
X559455Y13937D01*
X559855Y14337D01*
Y14737D01*
X559455D01*
X559055Y14337D01*
X558655Y14737D01*
X558255D01*
Y14337D01*
X558655Y13937D01*
X558255Y13537D01*
Y13137D01*
X548255D02*
X548655D01*
X549055Y13537D01*
X549455Y13137D01*
X549855D01*
Y13537D01*
X549455Y13937D01*
X549855Y14337D01*
Y14737D01*
X549455D01*
X549055Y14337D01*
X548655Y14737D01*
X548255D01*
Y14337D01*
X548655Y13937D01*
X548255Y13537D01*
Y13137D01*
X538255D02*
X538655D01*
X539055Y13537D01*
X539455Y13137D01*
X539855D01*
Y13537D01*
X539455Y13937D01*
X539855Y14337D01*
Y14737D01*
X539455D01*
X539055Y14337D01*
X538655Y14737D01*
X538255D01*
Y14337D01*
X538655Y13937D01*
X538255Y13537D01*
Y13137D01*
X588255Y3137D02*
X588655D01*
X589055Y3537D01*
X589455Y3137D01*
X589855D01*
Y3537D01*
X589455Y3937D01*
X589855Y4337D01*
Y4737D01*
X589455D01*
X589055Y4337D01*
X588655Y4737D01*
X588255D01*
Y4337D01*
X588655Y3937D01*
X588255Y3537D01*
Y3137D01*
X578255D02*
X578655D01*
X579055Y3537D01*
X579455Y3137D01*
X579855D01*
Y3537D01*
X579455Y3937D01*
X579855Y4337D01*
Y4737D01*
X579455D01*
X579055Y4337D01*
X578655Y4737D01*
X578255D01*
Y4337D01*
X578655Y3937D01*
X578255Y3537D01*
Y3137D01*
X568255D02*
X568655D01*
X569055Y3537D01*
X569455Y3137D01*
X569855D01*
Y3537D01*
X569455Y3937D01*
X569855Y4337D01*
Y4737D01*
X569455D01*
X569055Y4337D01*
X568655Y4737D01*
X568255D01*
Y4337D01*
X568655Y3937D01*
X568255Y3537D01*
Y3137D01*
X558255D02*
X558655D01*
X559055Y3537D01*
X559455Y3137D01*
X559855D01*
Y3537D01*
X559455Y3937D01*
X559855Y4337D01*
Y4737D01*
X559455D01*
X559055Y4337D01*
X558655Y4737D01*
X558255D01*
Y4337D01*
X558655Y3937D01*
X558255Y3537D01*
Y3137D01*
X548255D02*
X548655D01*
X549055Y3537D01*
X549455Y3137D01*
X549855D01*
Y3537D01*
X549455Y3937D01*
X549855Y4337D01*
Y4737D01*
X549455D01*
X549055Y4337D01*
X548655Y4737D01*
X548255D01*
Y4337D01*
X548655Y3937D01*
X548255Y3537D01*
Y3137D01*
X538255D02*
X538655D01*
X539055Y3537D01*
X539455Y3137D01*
X539855D01*
Y3537D01*
X539455Y3937D01*
X539855Y4337D01*
Y4737D01*
X539455D01*
X539055Y4337D01*
X538655Y4737D01*
X538255D01*
Y4337D01*
X538655Y3937D01*
X538255Y3537D01*
Y3137D01*
X1333Y1666D02*
X1000Y1999D01*
X333D01*
X0Y1666D01*
Y333D01*
X333Y0D01*
X1000D01*
X1333Y333D01*
X1333Y-376729D02*
X1000Y-376396D01*
X333D01*
X0Y-376729D01*
Y-378062D01*
X333Y-378395D01*
X1000D01*
X1333Y-378062D01*
X670538Y-74409D02*
Y-73076D01*
X671205Y-72410D01*
X671871Y-73076D01*
Y-74409D01*
Y-73410D01*
X670538D01*
X668438Y-74409D02*
Y-73076D01*
X669105Y-72410D01*
X669771Y-73076D01*
Y-74409D01*
Y-73410D01*
X668438D01*
X676772Y-54331D02*
Y-52998D01*
X677438Y-52331D01*
X678105Y-52998D01*
Y-54331D01*
Y-53331D01*
X676772D01*
Y-51575D02*
Y-50242D01*
X677438Y-49575D01*
X678105Y-50242D01*
Y-51575D01*
Y-50575D01*
X676772D01*
X84079Y-105653D02*
Y-104320D01*
X84746Y-103654D01*
X85412Y-104320D01*
Y-105653D01*
Y-104653D01*
X84079D01*
X62986Y-112803D02*
Y-111470D01*
X63653Y-110803D01*
X64319Y-111470D01*
Y-112803D01*
Y-111803D01*
X62986D01*
X62499Y-117255D02*
Y-115922D01*
X63165Y-115256D01*
X63832Y-115922D01*
Y-117255D01*
Y-116256D01*
X62499D01*
X141981Y-347043D02*
Y-345710D01*
X142648Y-345044D01*
X143314Y-345710D01*
Y-347043D01*
Y-346044D01*
X141981D01*
X142520Y-342913D02*
Y-341581D01*
X143186Y-340914D01*
X143853Y-341581D01*
Y-342913D01*
Y-341914D01*
X142520D01*
X198392Y-366842D02*
Y-365509D01*
X199059Y-364843D01*
X199725Y-365509D01*
Y-366842D01*
Y-365842D01*
X198392D01*
X196701Y-370523D02*
Y-369190D01*
X197367Y-368524D01*
X198034Y-369190D01*
Y-370523D01*
Y-369523D01*
X196701D01*
X680709Y-216929D02*
Y-215596D01*
X681375Y-214930D01*
X682042Y-215596D01*
Y-216929D01*
Y-215929D01*
X680709D01*
X671654Y-217323D02*
Y-215990D01*
X672320Y-215323D01*
X672986Y-215990D01*
Y-217323D01*
Y-216323D01*
X671654D01*
X585433Y-114961D02*
Y-113628D01*
X586099Y-112961D01*
X586766Y-113628D01*
Y-114961D01*
Y-113961D01*
X585433D01*
X584252Y-117717D02*
Y-116384D01*
X584918Y-115717D01*
X585585Y-116384D01*
Y-117717D01*
Y-116717D01*
X584252D01*
X366929Y-75984D02*
Y-74651D01*
X367596Y-73985D01*
X368262Y-74651D01*
Y-75984D01*
Y-74985D01*
X366929D01*
Y-83071D02*
Y-81738D01*
X367596Y-81072D01*
X368262Y-81738D01*
Y-83071D01*
Y-82071D01*
X366929D01*
Y-86614D02*
Y-85281D01*
X367596Y-84615D01*
X368262Y-85281D01*
Y-86614D01*
Y-85615D01*
X366929D01*
Y-89370D02*
Y-88037D01*
X367596Y-87371D01*
X368262Y-88037D01*
Y-89370D01*
Y-88370D01*
X366929D01*
Y-79528D02*
Y-78195D01*
X367596Y-77528D01*
X368262Y-78195D01*
Y-79528D01*
Y-78528D01*
X366929D01*
X679921Y-160236D02*
Y-158903D01*
X680588Y-158237D01*
X681254Y-158903D01*
Y-160236D01*
Y-159237D01*
X679921D01*
X684646Y-161811D02*
Y-160478D01*
X685312Y-159812D01*
X685979Y-160478D01*
Y-161811D01*
Y-160811D01*
X684646D01*
X689370Y-161417D02*
Y-160084D01*
X690036Y-159418D01*
X690703Y-160084D01*
Y-161417D01*
Y-160418D01*
X689370D01*
X689764Y-164567D02*
Y-163234D01*
X690430Y-162568D01*
X691097Y-163234D01*
Y-164567D01*
Y-163567D01*
X689764D01*
Y-168110D02*
Y-166777D01*
X690430Y-166111D01*
X691097Y-166777D01*
Y-168110D01*
Y-167111D01*
X689764D01*
X625000Y-48080D02*
Y-46747D01*
X625667Y-46081D01*
X626333Y-46747D01*
Y-48080D01*
Y-47081D01*
X625000D01*
X476945Y-173228D02*
Y-171896D01*
X477612Y-171229D01*
X478278Y-171896D01*
Y-173228D01*
Y-172229D01*
X476945D01*
X555512Y-218504D02*
Y-217171D01*
X556178Y-216505D01*
X556845Y-217171D01*
Y-218504D01*
Y-217504D01*
X555512D01*
X381496Y-127165D02*
Y-125832D01*
X382162Y-125166D01*
X382829Y-125832D01*
Y-127165D01*
Y-126166D01*
X381496D01*
X378740Y-123622D02*
Y-122289D01*
X379407Y-121623D01*
X380073Y-122289D01*
Y-123622D01*
Y-122622D01*
X378740D01*
X377559Y-135433D02*
Y-134100D01*
X378225Y-133434D01*
X378892Y-134100D01*
Y-135433D01*
Y-134433D01*
X377559D01*
X381890Y-137402D02*
Y-136069D01*
X382556Y-135402D01*
X383223Y-136069D01*
Y-137402D01*
Y-136402D01*
X381890D01*
X377559Y-142126D02*
Y-140793D01*
X378225Y-140127D01*
X378892Y-140793D01*
Y-142126D01*
Y-141126D01*
X377559D01*
X381496Y-140945D02*
Y-139612D01*
X382162Y-138945D01*
X382829Y-139612D01*
Y-140945D01*
Y-139945D01*
X381496D01*
X474016Y-176378D02*
Y-175045D01*
X474682Y-174379D01*
X475349Y-175045D01*
Y-176378D01*
Y-175378D01*
X474016D01*
X460186Y-175448D02*
Y-174115D01*
X460852Y-173448D01*
X461519Y-174115D01*
Y-175448D01*
Y-174448D01*
X460186D01*
X578168Y-80778D02*
Y-79445D01*
X578834Y-78779D01*
X579501Y-79445D01*
Y-80778D01*
Y-79778D01*
X578168D01*
X530027Y-172987D02*
Y-171655D01*
X530693Y-170988D01*
X531360Y-171655D01*
Y-172987D01*
Y-171988D01*
X530027D01*
X533044Y-176225D02*
Y-174892D01*
X533710Y-174226D01*
X534377Y-174892D01*
Y-176225D01*
Y-175225D01*
X533044D01*
X495669Y-222047D02*
Y-220714D01*
X496336Y-220048D01*
X497002Y-220714D01*
Y-222047D01*
Y-221048D01*
X495669D01*
X500394Y-222835D02*
Y-221502D01*
X501060Y-220835D01*
X501727Y-221502D01*
Y-222835D01*
Y-221835D01*
X500394D01*
X157480Y-361811D02*
Y-360478D01*
X158147Y-359812D01*
X158813Y-360478D01*
Y-361811D01*
Y-360811D01*
X157480D01*
X153543Y-358661D02*
Y-357329D01*
X154210Y-356662D01*
X154876Y-357329D01*
Y-358661D01*
Y-357662D01*
X153543D01*
Y-361811D02*
Y-360478D01*
X154210Y-359812D01*
X154876Y-360478D01*
Y-361811D01*
Y-360811D01*
X153543D01*
X155512Y-361811D02*
Y-360478D01*
X156178Y-359812D01*
X156845Y-360478D01*
Y-361811D01*
Y-360811D01*
X155512D01*
Y-358661D02*
Y-357329D01*
X156178Y-356662D01*
X156845Y-357329D01*
Y-358661D01*
Y-357662D01*
X155512D01*
X157480Y-358661D02*
Y-357329D01*
X158147Y-356662D01*
X158813Y-357329D01*
Y-358661D01*
Y-357662D01*
X157480D01*
X644488Y-170472D02*
Y-169140D01*
X645155Y-168473D01*
X645821Y-169140D01*
Y-170472D01*
Y-169473D01*
X644488D01*
X644619Y-166285D02*
Y-164952D01*
X645286Y-164285D01*
X645952Y-164952D01*
Y-166285D01*
Y-165285D01*
X644619D01*
X644569Y-162910D02*
Y-161577D01*
X645235Y-160911D01*
X645901Y-161577D01*
Y-162910D01*
Y-161911D01*
X644569D01*
X644488Y-159843D02*
Y-158510D01*
X645155Y-157843D01*
X645821Y-158510D01*
Y-159843D01*
Y-158843D01*
X644488D01*
X435827Y-103543D02*
Y-102210D01*
X436493Y-101544D01*
X437160Y-102210D01*
Y-103543D01*
Y-102544D01*
X435827D01*
X402719Y-112334D02*
Y-111001D01*
X403385Y-110334D01*
X404051Y-111001D01*
Y-112334D01*
Y-111334D01*
X402719D01*
X409900Y-136559D02*
Y-135227D01*
X410566Y-134560D01*
X411233Y-135227D01*
Y-136559D01*
Y-135560D01*
X409900D01*
X430492Y-136473D02*
Y-135140D01*
X431158Y-134474D01*
X431825Y-135140D01*
Y-136473D01*
Y-135473D01*
X430492D01*
X414567Y-137402D02*
Y-136069D01*
X415233Y-135402D01*
X415900Y-136069D01*
Y-137402D01*
Y-136402D01*
X414567D01*
X436614Y-136614D02*
Y-135281D01*
X437281Y-134615D01*
X437947Y-135281D01*
Y-136614D01*
Y-135615D01*
X436614D01*
X443307Y-111024D02*
Y-109691D01*
X443973Y-109024D01*
X444640Y-109691D01*
Y-111024D01*
Y-110024D01*
X443307D01*
X664966Y-316582D02*
Y-315249D01*
X665632Y-314583D01*
X666299Y-315249D01*
Y-316582D01*
Y-315583D01*
X664966D01*
X664961Y-325984D02*
Y-324651D01*
X665627Y-323985D01*
X666293Y-324651D01*
Y-325984D01*
Y-324985D01*
X664961D01*
X692037Y-315878D02*
Y-314545D01*
X692703Y-313878D01*
X693370Y-314545D01*
Y-315878D01*
Y-314878D01*
X692037D01*
X692126Y-322441D02*
Y-321108D01*
X692792Y-320442D01*
X693459Y-321108D01*
Y-322441D01*
Y-321441D01*
X692126D01*
X256897Y-112001D02*
Y-110668D01*
X257563Y-110001D01*
X258230Y-110668D01*
Y-112001D01*
Y-111001D01*
X256897D01*
X255118Y-118504D02*
Y-117171D01*
X255785Y-116505D01*
X256451Y-117171D01*
Y-118504D01*
Y-117504D01*
X255118D01*
X254376Y-125747D02*
Y-124414D01*
X255042Y-123747D01*
X255709Y-124414D01*
Y-125747D01*
Y-124747D01*
X254376D01*
X241250Y-126247D02*
Y-124914D01*
X241916Y-124248D01*
X242583Y-124914D01*
Y-126247D01*
Y-125247D01*
X241250D01*
X238189Y-116142D02*
Y-114809D01*
X238855Y-114142D01*
X239522Y-114809D01*
Y-116142D01*
Y-115142D01*
X238189D01*
X246063Y-111024D02*
Y-109691D01*
X246729Y-109024D01*
X247396Y-109691D01*
Y-111024D01*
Y-110024D01*
X246063D01*
X248425Y-129134D02*
Y-127801D01*
X249092Y-127135D01*
X249758Y-127801D01*
Y-129134D01*
Y-128134D01*
X248425D01*
X241077Y-118805D02*
Y-117472D01*
X241743Y-116805D01*
X242410Y-117472D01*
Y-118805D01*
Y-117805D01*
X241077D01*
X255512Y-121260D02*
Y-119927D01*
X256178Y-119261D01*
X256845Y-119927D01*
Y-121260D01*
Y-120260D01*
X255512D01*
X253713Y-109190D02*
Y-107857D01*
X254379Y-107191D01*
X255046Y-107857D01*
Y-109190D01*
Y-108190D01*
X253713D01*
X253690Y-111960D02*
Y-110627D01*
X254356Y-109960D01*
X255023Y-110627D01*
Y-111960D01*
Y-110960D01*
X253690D01*
X267717Y-123622D02*
Y-122289D01*
X268383Y-121623D01*
X269049Y-122289D01*
Y-123622D01*
Y-122622D01*
X267717D01*
X271654Y-122835D02*
Y-121502D01*
X272320Y-120835D01*
X272987Y-121502D01*
Y-122835D01*
Y-121835D01*
X271654D01*
X267323Y-132677D02*
Y-131344D01*
X267989Y-130678D01*
X268656Y-131344D01*
Y-132677D01*
Y-131677D01*
X267323D01*
X272047Y-131496D02*
Y-130163D01*
X272714Y-129497D01*
X273380Y-130163D01*
Y-131496D01*
Y-130496D01*
X272047D01*
X244664Y-106952D02*
Y-105619D01*
X245330Y-104953D01*
X245997Y-105619D01*
Y-106952D01*
Y-105952D01*
X244664D01*
X228824Y-104850D02*
Y-103517D01*
X229490Y-102851D01*
X230157Y-103517D01*
Y-104850D01*
Y-103850D01*
X228824D01*
X577953Y-83858D02*
Y-82525D01*
X578619Y-81859D01*
X579286Y-82525D01*
Y-83858D01*
Y-82859D01*
X577953D01*
X618898Y-82284D02*
Y-80951D01*
X619564Y-80284D01*
X620230Y-80951D01*
Y-82284D01*
Y-81284D01*
X618898D01*
X612205Y-87008D02*
Y-85675D01*
X612871Y-85009D01*
X613538Y-85675D01*
Y-87008D01*
Y-86008D01*
X612205D01*
X609055Y-92520D02*
Y-91187D01*
X609722Y-90520D01*
X610388Y-91187D01*
Y-92520D01*
Y-91520D01*
X609055D01*
X620959Y-100047D02*
Y-98715D01*
X621625Y-98048D01*
X622292Y-98715D01*
Y-100047D01*
Y-99048D01*
X620959D01*
X612598Y-100000D02*
Y-98667D01*
X613265Y-98001D01*
X613931Y-98667D01*
Y-100000D01*
Y-99000D01*
X612598D01*
X629134Y-102756D02*
Y-101423D01*
X629800Y-100757D01*
X630467Y-101423D01*
Y-102756D01*
Y-101756D01*
X629134D01*
X631814Y-83784D02*
Y-82451D01*
X632481Y-81785D01*
X633147Y-82451D01*
Y-83784D01*
Y-82785D01*
X631814D01*
X629101Y-90137D02*
Y-88804D01*
X629767Y-88138D01*
X630433Y-88804D01*
Y-90137D01*
Y-89137D01*
X629101D01*
X623228Y-93307D02*
Y-91974D01*
X623895Y-91308D01*
X624561Y-91974D01*
Y-93307D01*
Y-92307D01*
X623228D01*
X616535Y-84646D02*
Y-83313D01*
X617202Y-82646D01*
X617868Y-83313D01*
Y-84646D01*
Y-83646D01*
X616535D01*
X616929Y-100000D02*
Y-98667D01*
X617596Y-98001D01*
X618262Y-98667D01*
Y-100000D01*
Y-99000D01*
X616929D01*
X599279Y-82981D02*
Y-81648D01*
X599945Y-80981D01*
X600612Y-81648D01*
Y-82981D01*
Y-81981D01*
X599279D01*
X597227Y-77103D02*
Y-75770D01*
X597894Y-75104D01*
X598560Y-75770D01*
Y-77103D01*
Y-76103D01*
X597227D01*
X601745Y-98051D02*
Y-96718D01*
X602411Y-96051D01*
X603078Y-96718D01*
Y-98051D01*
Y-97051D01*
X601745D01*
X588372Y-100945D02*
Y-99612D01*
X589039Y-98945D01*
X589705Y-99612D01*
Y-100945D01*
Y-99945D01*
X588372D01*
X567323Y-94095D02*
Y-92762D01*
X567989Y-92095D01*
X568656Y-92762D01*
Y-94095D01*
Y-93095D01*
X567323D01*
X569291Y-91339D02*
Y-90006D01*
X569958Y-89339D01*
X570624Y-90006D01*
Y-91339D01*
Y-90339D01*
X569291D01*
X568504Y-88189D02*
Y-86856D01*
X569170Y-86190D01*
X569837Y-86856D01*
Y-88189D01*
Y-87189D01*
X568504D01*
X579921Y-101969D02*
Y-100636D01*
X580588Y-99969D01*
X581254Y-100636D01*
Y-101969D01*
Y-100969D01*
X579921D01*
X584763Y-100116D02*
Y-98783D01*
X585430Y-98116D01*
X586096Y-98783D01*
Y-100116D01*
Y-99116D01*
X584763D01*
X588976Y-86221D02*
Y-84888D01*
X589643Y-84221D01*
X590309Y-84888D01*
Y-86221D01*
Y-85221D01*
X588976D01*
X600394Y-87795D02*
Y-86462D01*
X601060Y-85796D01*
X601727Y-86462D01*
Y-87795D01*
Y-86796D01*
X600394D01*
X592520Y-93307D02*
Y-91974D01*
X593186Y-91308D01*
X593853Y-91974D01*
Y-93307D01*
Y-92307D01*
X592520D01*
X666929Y-98032D02*
Y-96699D01*
X667596Y-96032D01*
X668262Y-96699D01*
Y-98032D01*
Y-97032D01*
X666929D01*
X662539Y-107066D02*
Y-105733D01*
X663205Y-105066D01*
X663872Y-105733D01*
Y-107066D01*
Y-106066D01*
X662539D01*
X667717Y-106693D02*
Y-105360D01*
X668383Y-104694D01*
X669049Y-105360D01*
Y-106693D01*
Y-105693D01*
X667717D01*
X696762Y-63288D02*
Y-61955D01*
X697428Y-61289D01*
X698095Y-61955D01*
Y-63288D01*
Y-62288D01*
X696762D01*
X696577Y-51453D02*
Y-50120D01*
X697244Y-49453D01*
X697910Y-50120D01*
Y-51453D01*
Y-50453D01*
X696577D01*
X675591Y-42520D02*
Y-41187D01*
X676257Y-40520D01*
X676923Y-41187D01*
Y-42520D01*
Y-41520D01*
X675591D01*
X685716Y-22157D02*
Y-20824D01*
X686382Y-20158D01*
X687049Y-20824D01*
Y-22157D01*
Y-21157D01*
X685716D01*
X679517Y-26553D02*
Y-25220D01*
X680184Y-24553D01*
X680850Y-25220D01*
Y-26553D01*
Y-25553D01*
X679517D01*
Y-37023D02*
Y-35690D01*
X680184Y-35023D01*
X680850Y-35690D01*
Y-37023D01*
Y-36023D01*
X679517D01*
X693915Y-33393D02*
Y-32060D01*
X694581Y-31394D01*
X695247Y-32060D01*
Y-33393D01*
Y-32393D01*
X693915D01*
X686728Y-33442D02*
Y-32109D01*
X687395Y-31443D01*
X688061Y-32109D01*
Y-33442D01*
Y-32443D01*
X686728D01*
X686319Y-43553D02*
Y-42220D01*
X686985Y-41554D01*
X687652Y-42220D01*
Y-43553D01*
Y-42553D01*
X686319D01*
X683127Y-66209D02*
Y-64876D01*
X683794Y-64210D01*
X684460Y-64876D01*
Y-66209D01*
Y-65209D01*
X683127D01*
X689466Y-66165D02*
Y-64833D01*
X690133Y-64166D01*
X690799Y-64833D01*
Y-66165D01*
Y-65166D01*
X689466D01*
X680082Y-64183D02*
Y-62850D01*
X680748Y-62184D01*
X681415Y-62850D01*
Y-64183D01*
Y-63184D01*
X680082D01*
X675926Y-72691D02*
Y-71358D01*
X676592Y-70691D01*
X677259Y-71358D01*
Y-72691D01*
Y-71691D01*
X675926D01*
X660719Y-75726D02*
Y-74394D01*
X661385Y-73727D01*
X662052Y-74394D01*
Y-75726D01*
Y-74727D01*
X660719D01*
X694095Y-62205D02*
Y-60872D01*
X694761Y-60205D01*
X695427Y-60872D01*
Y-62205D01*
Y-61205D01*
X694095D01*
X693977Y-53201D02*
Y-51868D01*
X694643Y-51201D01*
X695310Y-51868D01*
Y-53201D01*
Y-52201D01*
X693977D01*
X676378Y-83858D02*
Y-82525D01*
X677044Y-81859D01*
X677711Y-82525D01*
Y-83858D01*
Y-82859D01*
X676378D01*
X538583Y-111811D02*
Y-110478D01*
X539249Y-109812D01*
X539916Y-110478D01*
Y-111811D01*
Y-110811D01*
X538583D01*
X539233Y-115729D02*
Y-114396D01*
X539899Y-113730D01*
X540566Y-114396D01*
Y-115729D01*
Y-114729D01*
X539233D01*
X569092Y-108048D02*
Y-106715D01*
X569758Y-106049D01*
X570425Y-106715D01*
Y-108048D01*
Y-107049D01*
X569092D01*
X546386Y-109024D02*
Y-107691D01*
X547053Y-107025D01*
X547719Y-107691D01*
Y-109024D01*
Y-108025D01*
X546386D01*
X548093Y-185219D02*
Y-183886D01*
X548759Y-183220D01*
X549426Y-183886D01*
Y-185219D01*
Y-184219D01*
X548093D01*
X548425Y-181890D02*
Y-180557D01*
X549092Y-179890D01*
X549758Y-180557D01*
Y-181890D01*
Y-180890D01*
X548425D01*
X548819Y-178740D02*
Y-177407D01*
X549485Y-176741D01*
X550152Y-177407D01*
Y-178740D01*
Y-177741D01*
X548819D01*
X547244Y-157087D02*
Y-155754D01*
X547910Y-155087D01*
X548577Y-155754D01*
Y-157087D01*
Y-156087D01*
X547244D01*
Y-144488D02*
Y-143155D01*
X547910Y-142489D01*
X548577Y-143155D01*
Y-144488D01*
Y-143489D01*
X547244D01*
X524409Y-135827D02*
Y-134494D01*
X525076Y-133827D01*
X525742Y-134494D01*
Y-135827D01*
Y-134827D01*
X524409D01*
X531801Y-127495D02*
Y-126162D01*
X532467Y-125496D01*
X533134Y-126162D01*
Y-127495D01*
Y-126496D01*
X531801D01*
X539900Y-140766D02*
Y-139433D01*
X540567Y-138766D01*
X541233Y-139433D01*
Y-140766D01*
Y-139766D01*
X539900D01*
X570472Y-137795D02*
Y-136462D01*
X571139Y-135796D01*
X571805Y-136462D01*
Y-137795D01*
Y-136796D01*
X570472D01*
X579921Y-133465D02*
Y-132132D01*
X580588Y-131465D01*
X581254Y-132132D01*
Y-133465D01*
Y-132465D01*
X579921D01*
X574409Y-133465D02*
Y-132132D01*
X575076Y-131465D01*
X575742Y-132132D01*
Y-133465D01*
Y-132465D01*
X574409D01*
X570866Y-133465D02*
Y-132132D01*
X571533Y-131465D01*
X572199Y-132132D01*
Y-133465D01*
Y-132465D01*
X570866D01*
X572047Y-129921D02*
Y-128588D01*
X572714Y-127922D01*
X573380Y-128588D01*
Y-129921D01*
Y-128922D01*
X572047D01*
X576378Y-129921D02*
Y-128588D01*
X577044Y-127922D01*
X577711Y-128588D01*
Y-129921D01*
Y-128922D01*
X576378D01*
X580315Y-129921D02*
Y-128588D01*
X580981Y-127922D01*
X581648Y-128588D01*
Y-129921D01*
Y-128922D01*
X580315D01*
X646457Y-156693D02*
Y-155360D01*
X647123Y-154694D01*
X647790Y-155360D01*
Y-156693D01*
Y-155693D01*
X646457D01*
X642520Y-156693D02*
Y-155360D01*
X643186Y-154694D01*
X643853Y-155360D01*
Y-156693D01*
Y-155693D01*
X642520D01*
X635039Y-216142D02*
Y-214809D01*
X635706Y-214142D01*
X636372Y-214809D01*
Y-216142D01*
Y-215142D01*
X635039D01*
X608661Y-236221D02*
Y-234888D01*
X609328Y-234221D01*
X609994Y-234888D01*
Y-236221D01*
Y-235221D01*
X608661D01*
X572441Y-227165D02*
Y-225833D01*
X573107Y-225166D01*
X573774Y-225833D01*
Y-227165D01*
Y-226166D01*
X572441D01*
X678441Y-292586D02*
Y-291253D01*
X679107Y-290587D01*
X679774Y-291253D01*
Y-292586D01*
Y-291587D01*
X678441D01*
X678346Y-297244D02*
Y-295911D01*
X679013Y-295245D01*
X679679Y-295911D01*
Y-297244D01*
Y-296244D01*
X678346D01*
X639764Y-283858D02*
Y-282525D01*
X640430Y-281859D01*
X641097Y-282525D01*
Y-283858D01*
Y-282859D01*
X639764D01*
X554724Y-294882D02*
Y-293549D01*
X555391Y-292882D01*
X556057Y-293549D01*
Y-294882D01*
Y-293882D01*
X554724D01*
X565354Y-292913D02*
Y-291581D01*
X566021Y-290914D01*
X566687Y-291581D01*
Y-292913D01*
Y-291914D01*
X565354D01*
X630577Y-278001D02*
Y-276668D01*
X631243Y-276002D01*
X631910Y-276668D01*
Y-278001D01*
Y-277002D01*
X630577D01*
X582874Y-294291D02*
Y-292958D01*
X583540Y-292292D01*
X584207Y-292958D01*
Y-294291D01*
Y-293292D01*
X582874D01*
X680709Y-212205D02*
Y-210872D01*
X681375Y-210205D01*
X682042Y-210872D01*
Y-212205D01*
Y-211205D01*
X680709D01*
X673622Y-213779D02*
Y-212447D01*
X674289Y-211780D01*
X674955Y-212447D01*
Y-213779D01*
Y-212780D01*
X673622D01*
X669685Y-213779D02*
Y-212447D01*
X670352Y-211780D01*
X671018Y-212447D01*
Y-213779D01*
Y-212780D01*
X669685D01*
X666142Y-212992D02*
Y-211659D01*
X666808Y-210993D01*
X667475Y-211659D01*
Y-212992D01*
Y-211993D01*
X666142D01*
X599564Y-178940D02*
Y-177607D01*
X600231Y-176941D01*
X600897Y-177607D01*
Y-178940D01*
Y-177940D01*
X599564D01*
X594882Y-179134D02*
Y-177801D01*
X595548Y-177135D01*
X596215Y-177801D01*
Y-179134D01*
Y-178134D01*
X594882D01*
X589764Y-179134D02*
Y-177801D01*
X590430Y-177135D01*
X591097Y-177801D01*
Y-179134D01*
Y-178134D01*
X589764D01*
X584646Y-178740D02*
Y-177407D01*
X585312Y-176741D01*
X585979Y-177407D01*
Y-178740D01*
Y-177741D01*
X584646D01*
X635827Y-187795D02*
Y-186462D01*
X636493Y-185796D01*
X637160Y-186462D01*
Y-187795D01*
Y-186796D01*
X635827D01*
X635433Y-184252D02*
Y-182919D01*
X636099Y-182253D01*
X636766Y-182919D01*
Y-184252D01*
Y-183252D01*
X635433D01*
X652756Y-164961D02*
Y-163628D01*
X653422Y-162961D01*
X654089Y-163628D01*
Y-164961D01*
Y-163961D01*
X652756D01*
X657480Y-164567D02*
Y-163234D01*
X658147Y-162568D01*
X658813Y-163234D01*
Y-164567D01*
Y-163567D01*
X657480D01*
X662992Y-164961D02*
Y-163628D01*
X663659Y-162961D01*
X664325Y-163628D01*
Y-164961D01*
Y-163961D01*
X662992D01*
X668504Y-164961D02*
Y-163628D01*
X669170Y-162961D01*
X669837Y-163628D01*
Y-164961D01*
Y-163961D01*
X668504D01*
X681496Y-179528D02*
Y-178195D01*
X682163Y-177528D01*
X682829Y-178195D01*
Y-179528D01*
Y-178528D01*
X681496D01*
X677165Y-172441D02*
Y-171108D01*
X677832Y-170442D01*
X678498Y-171108D01*
Y-172441D01*
Y-171441D01*
X677165D01*
X673228Y-172441D02*
Y-171108D01*
X673895Y-170442D01*
X674561Y-171108D01*
Y-172441D01*
Y-171441D01*
X673228D01*
X675197Y-200000D02*
Y-198667D01*
X675863Y-198001D01*
X676530Y-198667D01*
Y-200000D01*
Y-199000D01*
X675197D01*
X678740Y-200000D02*
Y-198667D01*
X679407Y-198001D01*
X680073Y-198667D01*
Y-200000D01*
Y-199000D01*
X678740D01*
X681890Y-200000D02*
Y-198667D01*
X682556Y-198001D01*
X683223Y-198667D01*
Y-200000D01*
Y-199000D01*
X681890D01*
Y-196850D02*
Y-195518D01*
X682556Y-194851D01*
X683223Y-195518D01*
Y-196850D01*
Y-195851D01*
X681890D01*
X678740Y-196850D02*
Y-195518D01*
X679407Y-194851D01*
X680073Y-195518D01*
Y-196850D01*
Y-195851D01*
X678740D01*
X675591Y-196457D02*
Y-195124D01*
X676257Y-194457D01*
X676923Y-195124D01*
Y-196457D01*
Y-195457D01*
X675591D01*
X652756Y-218504D02*
Y-217171D01*
X653422Y-216505D01*
X654089Y-217171D01*
Y-218504D01*
Y-217504D01*
X652756D01*
X650000Y-231102D02*
Y-229769D01*
X650666Y-229103D01*
X651333Y-229769D01*
Y-231102D01*
Y-230103D01*
X650000D01*
X646434Y-231245D02*
Y-229912D01*
X647100Y-229246D01*
X647767Y-229912D01*
Y-231245D01*
Y-230245D01*
X646434D01*
X598425Y-198819D02*
Y-197486D01*
X599092Y-196820D01*
X599758Y-197486D01*
Y-198819D01*
Y-197819D01*
X598425D01*
X595276Y-198819D02*
Y-197486D01*
X595942Y-196820D01*
X596608Y-197486D01*
Y-198819D01*
Y-197819D01*
X595276D01*
X592126Y-198819D02*
Y-197486D01*
X592792Y-196820D01*
X593459Y-197486D01*
Y-198819D01*
Y-197819D01*
X592126D01*
X589764Y-198819D02*
Y-197486D01*
X590430Y-196820D01*
X591097Y-197486D01*
Y-198819D01*
Y-197819D01*
X589764D01*
X587008Y-198819D02*
Y-197486D01*
X587674Y-196820D01*
X588341Y-197486D01*
Y-198819D01*
Y-197819D01*
X587008D01*
X570079Y-200000D02*
Y-198667D01*
X570745Y-198001D01*
X571412Y-198667D01*
Y-200000D01*
Y-199000D01*
X570079D01*
X549298Y-191988D02*
Y-190655D01*
X549965Y-189989D01*
X550631Y-190655D01*
Y-191988D01*
Y-190988D01*
X549298D01*
X600000Y-248425D02*
Y-247092D01*
X600666Y-246426D01*
X601333Y-247092D01*
Y-248425D01*
Y-247426D01*
X600000D01*
X616535Y-255512D02*
Y-254179D01*
X617202Y-253513D01*
X617868Y-254179D01*
Y-255512D01*
Y-254512D01*
X616535D01*
X612205Y-251575D02*
Y-250242D01*
X612871Y-249575D01*
X613538Y-250242D01*
Y-251575D01*
Y-250575D01*
X612205D01*
X624803Y-255906D02*
Y-254573D01*
X625470Y-253906D01*
X626136Y-254573D01*
Y-255906D01*
Y-254906D01*
X624803D01*
Y-251575D02*
Y-250242D01*
X625470Y-249575D01*
X626136Y-250242D01*
Y-251575D01*
Y-250575D01*
X624803D01*
X624409Y-248031D02*
Y-246699D01*
X625076Y-246032D01*
X625742Y-246699D01*
Y-248031D01*
Y-247032D01*
X624409D01*
X611417Y-247638D02*
Y-246305D01*
X612084Y-245638D01*
X612750Y-246305D01*
Y-247638D01*
Y-246638D01*
X611417D01*
X605118Y-244488D02*
Y-243155D01*
X605785Y-242489D01*
X606451Y-243155D01*
Y-244488D01*
Y-243489D01*
X605118D01*
X673228Y-251181D02*
Y-249848D01*
X673895Y-249182D01*
X674561Y-249848D01*
Y-251181D01*
Y-250181D01*
X673228D01*
X672835Y-257087D02*
Y-255754D01*
X673501Y-255087D01*
X674168Y-255754D01*
Y-257087D01*
Y-256087D01*
X672835D01*
X673622Y-261417D02*
Y-260084D01*
X674289Y-259418D01*
X674955Y-260084D01*
Y-261417D01*
Y-260418D01*
X673622D01*
X676378Y-266142D02*
Y-264809D01*
X677044Y-264142D01*
X677711Y-264809D01*
Y-266142D01*
Y-265142D01*
X676378D01*
X676772Y-270866D02*
Y-269533D01*
X677438Y-268867D01*
X678105Y-269533D01*
Y-270866D01*
Y-269866D01*
X676772D01*
X671260Y-274803D02*
Y-273470D01*
X671926Y-272804D01*
X672593Y-273470D01*
Y-274803D01*
Y-273803D01*
X671260D01*
Y-278740D02*
Y-277407D01*
X671926Y-276741D01*
X672593Y-277407D01*
Y-278740D01*
Y-277741D01*
X671260D01*
X671654Y-283071D02*
Y-281738D01*
X672320Y-281071D01*
X672986Y-281738D01*
Y-283071D01*
Y-282071D01*
X671654D01*
X683858Y-310630D02*
Y-309297D01*
X684525Y-308631D01*
X685191Y-309297D01*
Y-310630D01*
Y-309630D01*
X683858D01*
X683716Y-298538D02*
Y-297205D01*
X684383Y-296539D01*
X685049Y-297205D01*
Y-298538D01*
Y-297538D01*
X683716D01*
X651575Y-275197D02*
Y-273864D01*
X652241Y-273198D01*
X652908Y-273864D01*
Y-275197D01*
Y-274197D01*
X651575D01*
X648819Y-278740D02*
Y-277407D01*
X649485Y-276741D01*
X650152Y-277407D01*
Y-278740D01*
Y-277741D01*
X648819D01*
X652362Y-279528D02*
Y-278195D01*
X653029Y-277528D01*
X653695Y-278195D01*
Y-279528D01*
Y-278528D01*
X652362D01*
X657087Y-279528D02*
Y-278195D01*
X657753Y-277528D01*
X658420Y-278195D01*
Y-279528D01*
Y-278528D01*
X657087D01*
X654331Y-283858D02*
Y-282525D01*
X654997Y-281859D01*
X655664Y-282525D01*
Y-283858D01*
Y-282859D01*
X654331D01*
X650000Y-283858D02*
Y-282525D01*
X650666Y-281859D01*
X651333Y-282525D01*
Y-283858D01*
Y-282859D01*
X650000D01*
X646457Y-283858D02*
Y-282525D01*
X647123Y-281859D01*
X647790Y-282525D01*
Y-283858D01*
Y-282859D01*
X646457D01*
X637795Y-297638D02*
Y-296305D01*
X638462Y-295638D01*
X639128Y-296305D01*
Y-297638D01*
Y-296638D01*
X637795D01*
X585039Y-249606D02*
Y-248273D01*
X585706Y-247607D01*
X586372Y-248273D01*
Y-249606D01*
Y-248607D01*
X585039D01*
X590551Y-266535D02*
Y-265202D01*
X591218Y-264536D01*
X591884Y-265202D01*
Y-266535D01*
Y-265536D01*
X590551D01*
X588189Y-263386D02*
Y-262053D01*
X588855Y-261386D01*
X589522Y-262053D01*
Y-263386D01*
Y-262386D01*
X588189D01*
X585433Y-253937D02*
Y-252604D01*
X586099Y-251938D01*
X586766Y-252604D01*
Y-253937D01*
Y-252937D01*
X585433D01*
Y-257480D02*
Y-256147D01*
X586099Y-255481D01*
X586766Y-256147D01*
Y-257480D01*
Y-256481D01*
X585433D01*
X581496Y-257480D02*
Y-256147D01*
X582163Y-255481D01*
X582829Y-256147D01*
Y-257480D01*
Y-256481D01*
X581496D01*
X577953Y-257480D02*
Y-256147D01*
X578619Y-255481D01*
X579286Y-256147D01*
Y-257480D01*
Y-256481D01*
X577953D01*
X559842Y-257087D02*
Y-255754D01*
X560509Y-255087D01*
X561175Y-255754D01*
Y-257087D01*
Y-256087D01*
X559842D01*
X579134Y-195276D02*
Y-193943D01*
X579800Y-193276D01*
X580467Y-193943D01*
Y-195276D01*
Y-194276D01*
X579134D01*
X574803Y-195276D02*
Y-193943D01*
X575470Y-193276D01*
X576136Y-193943D01*
Y-195276D01*
Y-194276D01*
X574803D01*
X577953Y-198819D02*
Y-197486D01*
X578619Y-196820D01*
X579286Y-197486D01*
Y-198819D01*
Y-197819D01*
X577953D01*
X590158Y-226378D02*
Y-225045D01*
X590824Y-224379D01*
X591490Y-225045D01*
Y-226378D01*
Y-225378D01*
X590158D01*
X586221Y-226772D02*
Y-225439D01*
X586887Y-224772D01*
X587553Y-225439D01*
Y-226772D01*
Y-225772D01*
X586221D01*
X579921Y-227559D02*
Y-226226D01*
X580588Y-225560D01*
X581254Y-226226D01*
Y-227559D01*
Y-226559D01*
X579921D01*
X576772Y-228740D02*
Y-227407D01*
X577438Y-226741D01*
X578105Y-227407D01*
Y-228740D01*
Y-227741D01*
X576772D01*
X637008Y-238583D02*
Y-237250D01*
X637674Y-236583D01*
X638341Y-237250D01*
Y-238583D01*
Y-237583D01*
X637008D01*
X608661Y-242126D02*
Y-240793D01*
X609328Y-240127D01*
X609994Y-240793D01*
Y-242126D01*
Y-241126D01*
X608661D01*
X590551Y-242520D02*
Y-241187D01*
X591218Y-240520D01*
X591884Y-241187D01*
Y-242520D01*
Y-241520D01*
X590551D01*
X586537Y-234843D02*
Y-233510D01*
X587204Y-232844D01*
X587870Y-233510D01*
Y-234843D01*
Y-233844D01*
X586537D01*
X546850Y-213779D02*
Y-212447D01*
X547517Y-211780D01*
X548183Y-212447D01*
Y-213779D01*
Y-212780D01*
X546850D01*
X548819Y-196063D02*
Y-194730D01*
X549485Y-194064D01*
X550152Y-194730D01*
Y-196063D01*
Y-195063D01*
X548819D01*
X547244Y-203150D02*
Y-201817D01*
X547910Y-201150D01*
X548577Y-201817D01*
Y-203150D01*
Y-202150D01*
X547244D01*
X554724Y-207874D02*
Y-206541D01*
X555391Y-205875D01*
X556057Y-206541D01*
Y-207874D01*
Y-206874D01*
X554724D01*
X549213Y-207874D02*
Y-206541D01*
X549879Y-205875D01*
X550546Y-206541D01*
Y-207874D01*
Y-206874D01*
X549213D01*
X569291Y-194095D02*
Y-192762D01*
X569958Y-192095D01*
X570624Y-192762D01*
Y-194095D01*
Y-193095D01*
X569291D01*
X581496Y-198819D02*
Y-197486D01*
X582163Y-196820D01*
X582829Y-197486D01*
Y-198819D01*
Y-197819D01*
X581496D01*
X573622Y-198819D02*
Y-197486D01*
X574289Y-196820D01*
X574955Y-197486D01*
Y-198819D01*
Y-197819D01*
X573622D01*
X571162Y-284136D02*
Y-282803D01*
X571829Y-282137D01*
X572495Y-282803D01*
Y-284136D01*
Y-283137D01*
X571162D01*
X577953Y-284646D02*
Y-283313D01*
X578619Y-282646D01*
X579286Y-283313D01*
Y-284646D01*
Y-283646D01*
X577953D01*
X574803Y-284252D02*
Y-282919D01*
X575470Y-282253D01*
X576136Y-282919D01*
Y-284252D01*
Y-283252D01*
X574803D01*
X568110Y-284252D02*
Y-282919D01*
X568777Y-282253D01*
X569443Y-282919D01*
Y-284252D01*
Y-283252D01*
X568110D01*
X567717Y-259055D02*
Y-257722D01*
X568383Y-257056D01*
X569049Y-257722D01*
Y-259055D01*
Y-258055D01*
X567717D01*
X566535Y-255906D02*
Y-254573D01*
X567202Y-253906D01*
X567868Y-254573D01*
Y-255906D01*
Y-254906D01*
X566535D01*
X570079Y-255906D02*
Y-254573D01*
X570745Y-253906D01*
X571412Y-254573D01*
Y-255906D01*
Y-254906D01*
X570079D01*
X548425Y-253543D02*
Y-252210D01*
X549092Y-251544D01*
X549758Y-252210D01*
Y-253543D01*
Y-252544D01*
X548425D01*
X545669Y-253937D02*
Y-252604D01*
X546336Y-251938D01*
X547002Y-252604D01*
Y-253937D01*
Y-252937D01*
X545669D01*
X545128Y-280872D02*
Y-279539D01*
X545794Y-278873D01*
X546461Y-279539D01*
Y-280872D01*
Y-279872D01*
X545128D01*
X544909Y-287437D02*
Y-286104D01*
X545576Y-285437D01*
X546242Y-286104D01*
Y-287437D01*
Y-286437D01*
X544909D01*
X545276Y-294094D02*
Y-292762D01*
X545942Y-292095D01*
X546608Y-292762D01*
Y-294094D01*
Y-293095D01*
X545276D01*
Y-275197D02*
Y-273864D01*
X545942Y-273198D01*
X546608Y-273864D01*
Y-275197D01*
Y-274197D01*
X545276D01*
Y-270866D02*
Y-269533D01*
X545942Y-268867D01*
X546608Y-269533D01*
Y-270866D01*
Y-269866D01*
X545276D01*
X544488Y-265748D02*
Y-264415D01*
X545155Y-263749D01*
X545821Y-264415D01*
Y-265748D01*
Y-264748D01*
X544488D01*
X557087Y-261417D02*
Y-260084D01*
X557753Y-259418D01*
X558420Y-260084D01*
Y-261417D01*
Y-260418D01*
X557087D01*
X556628Y-258042D02*
Y-256709D01*
X557294Y-256043D01*
X557961Y-256709D01*
Y-258042D01*
Y-257042D01*
X556628D01*
X569548Y-287223D02*
Y-285890D01*
X570214Y-285224D01*
X570880Y-285890D01*
Y-287223D01*
Y-286224D01*
X569548D01*
X595276Y-291732D02*
Y-290399D01*
X595942Y-289733D01*
X596608Y-290399D01*
Y-291732D01*
Y-290733D01*
X595276D01*
X612598Y-291732D02*
Y-290399D01*
X613265Y-289733D01*
X613931Y-290399D01*
Y-291732D01*
Y-290733D01*
X612598D01*
X627559Y-296457D02*
Y-295124D01*
X628226Y-294457D01*
X628892Y-295124D01*
Y-296457D01*
Y-295457D01*
X627559D01*
X563386Y-257874D02*
Y-256541D01*
X564052Y-255875D01*
X564719Y-256541D01*
Y-257874D01*
Y-256874D01*
X563386D01*
X572441Y-258268D02*
Y-256935D01*
X573107Y-256268D01*
X573774Y-256935D01*
Y-258268D01*
Y-257268D01*
X572441D01*
X475984Y-127165D02*
Y-125832D01*
X476651Y-125166D01*
X477317Y-125832D01*
Y-127165D01*
Y-126166D01*
X475984D01*
X480120Y-132365D02*
Y-131032D01*
X480786Y-130366D01*
X481453Y-131032D01*
Y-132365D01*
Y-131365D01*
X480120D01*
X469685Y-133465D02*
Y-132132D01*
X470352Y-131465D01*
X471018Y-132132D01*
Y-133465D01*
Y-132465D01*
X469685D01*
X473228Y-105905D02*
Y-104573D01*
X473895Y-103906D01*
X474561Y-104573D01*
Y-105905D01*
Y-104906D01*
X473228D01*
X488583Y-132283D02*
Y-130951D01*
X489249Y-130284D01*
X489916Y-130951D01*
Y-132283D01*
Y-131284D01*
X488583D01*
X506299Y-129921D02*
Y-128588D01*
X506966Y-127922D01*
X507632Y-128588D01*
Y-129921D01*
Y-128922D01*
X506299D01*
X498032Y-132283D02*
Y-130951D01*
X498698Y-130284D01*
X499364Y-130951D01*
Y-132283D01*
Y-131284D01*
X498032D01*
X506207Y-127333D02*
Y-126000D01*
X506873Y-125333D01*
X507540Y-126000D01*
Y-127333D01*
Y-126333D01*
X506207D01*
X505905Y-123622D02*
Y-122289D01*
X506572Y-121623D01*
X507238Y-122289D01*
Y-123622D01*
Y-122622D01*
X505905D01*
X472441Y-113779D02*
Y-112447D01*
X473107Y-111780D01*
X473774Y-112447D01*
Y-113779D01*
Y-112780D01*
X472441D01*
X483484Y-105840D02*
Y-104507D01*
X484150Y-103840D01*
X484817Y-104507D01*
Y-105840D01*
Y-104840D01*
X483484D01*
X504703Y-106672D02*
Y-105339D01*
X505370Y-104673D01*
X506036Y-105339D01*
Y-106672D01*
Y-105673D01*
X504703D01*
X508268Y-117323D02*
Y-115990D01*
X508934Y-115323D01*
X509601Y-115990D01*
Y-117323D01*
Y-116323D01*
X508268D01*
X501669Y-116601D02*
Y-115268D01*
X502335Y-114602D01*
X503002Y-115268D01*
Y-116601D01*
Y-115601D01*
X501669D01*
X500313Y-105734D02*
Y-104401D01*
X500979Y-103734D01*
X501646Y-104401D01*
Y-105734D01*
Y-104734D01*
X500313D01*
X476772Y-123622D02*
Y-122289D01*
X477438Y-121623D01*
X478105Y-122289D01*
Y-123622D01*
Y-122622D01*
X476772D01*
X470472Y-123622D02*
Y-122289D01*
X471139Y-121623D01*
X471805Y-122289D01*
Y-123622D01*
Y-122622D01*
X470472D01*
X444507Y-309009D02*
Y-307676D01*
X445174Y-307010D01*
X445840Y-307676D01*
Y-309009D01*
Y-308009D01*
X444507D01*
X448819Y-309055D02*
Y-307722D01*
X449485Y-307056D01*
X450152Y-307722D01*
Y-309055D01*
Y-308055D01*
X448819D01*
X457480Y-306693D02*
Y-305360D01*
X458147Y-304694D01*
X458813Y-305360D01*
Y-306693D01*
Y-305693D01*
X457480D01*
X451575Y-309055D02*
Y-307722D01*
X452241Y-307056D01*
X452908Y-307722D01*
Y-309055D01*
Y-308055D01*
X451575D01*
X437048Y-308863D02*
Y-307530D01*
X437715Y-306863D01*
X438381Y-307530D01*
Y-308863D01*
Y-307863D01*
X437048D01*
X431102Y-308268D02*
Y-306935D01*
X431769Y-306268D01*
X432435Y-306935D01*
Y-308268D01*
Y-307268D01*
X431102D01*
X461811Y-327165D02*
Y-325833D01*
X462477Y-325166D01*
X463144Y-325833D01*
Y-327165D01*
Y-326166D01*
X461811D01*
X456693Y-327165D02*
Y-325833D01*
X457359Y-325166D01*
X458026Y-325833D01*
Y-327165D01*
Y-326166D01*
X456693D01*
X454724Y-327165D02*
Y-325833D01*
X455391Y-325166D01*
X456057Y-325833D01*
Y-327165D01*
Y-326166D01*
X454724D01*
X450394Y-327165D02*
Y-325833D01*
X451060Y-325166D01*
X451727Y-325833D01*
Y-327165D01*
Y-326166D01*
X450394D01*
X448032Y-327165D02*
Y-325833D01*
X448698Y-325166D01*
X449364Y-325833D01*
Y-327165D01*
Y-326166D01*
X448032D01*
X443701Y-327165D02*
Y-325833D01*
X444367Y-325166D01*
X445034Y-325833D01*
Y-327165D01*
Y-326166D01*
X443701D01*
X441732Y-327165D02*
Y-325833D01*
X442399Y-325166D01*
X443065Y-325833D01*
Y-327165D01*
Y-326166D01*
X441732D01*
X436614Y-327165D02*
Y-325833D01*
X437281Y-325166D01*
X437947Y-325833D01*
Y-327165D01*
Y-326166D01*
X436614D01*
X429528Y-326772D02*
Y-325439D01*
X430194Y-324772D01*
X430861Y-325439D01*
Y-326772D01*
Y-325772D01*
X429528D01*
X434646Y-327559D02*
Y-326226D01*
X435312Y-325560D01*
X435979Y-326226D01*
Y-327559D01*
Y-326559D01*
X434646D01*
X518337Y-159634D02*
Y-158301D01*
X519004Y-157635D01*
X519670Y-158301D01*
Y-159634D01*
Y-158634D01*
X518337D01*
X515702Y-162803D02*
Y-161470D01*
X516369Y-160803D01*
X517035Y-161470D01*
Y-162803D01*
Y-161803D01*
X515702D01*
X498693Y-188351D02*
Y-187018D01*
X499359Y-186351D01*
X500026Y-187018D01*
Y-188351D01*
Y-187351D01*
X498693D01*
X498819Y-183858D02*
Y-182525D01*
X499485Y-181859D01*
X500152Y-182525D01*
Y-183858D01*
Y-182859D01*
X498819D01*
X499111Y-179528D02*
Y-178195D01*
X499777Y-177529D01*
X500444Y-178195D01*
Y-179528D01*
Y-178529D01*
X499111D01*
X658114Y-56714D02*
Y-55381D01*
X658781Y-54715D01*
X659447Y-55381D01*
Y-56714D01*
Y-55715D01*
X658114D01*
X657445Y-63525D02*
Y-62193D01*
X658112Y-61526D01*
X658778Y-62193D01*
Y-63525D01*
Y-62526D01*
X657445D01*
X658053Y-71188D02*
Y-69855D01*
X658720Y-69189D01*
X659386Y-69855D01*
Y-71188D01*
Y-70188D01*
X658053D01*
X623511Y-62552D02*
Y-61220D01*
X624177Y-60553D01*
X624844Y-61220D01*
Y-62552D01*
Y-61553D01*
X623511D01*
X623228Y-55118D02*
Y-53785D01*
X623895Y-53119D01*
X624561Y-53785D01*
Y-55118D01*
Y-54118D01*
X623228D01*
X623622Y-70866D02*
Y-69533D01*
X624289Y-68867D01*
X624955Y-69533D01*
Y-70866D01*
Y-69867D01*
X623622D01*
X43701Y-29921D02*
Y-28588D01*
X44367Y-27922D01*
X45034Y-28588D01*
Y-29921D01*
Y-28922D01*
X43701D01*
X55905Y-31496D02*
Y-30163D01*
X56572Y-29497D01*
X57238Y-30163D01*
Y-31496D01*
Y-30496D01*
X55905D01*
X111024Y-33071D02*
Y-31738D01*
X111690Y-31071D01*
X112356Y-31738D01*
Y-33071D01*
Y-32071D01*
X111024D01*
X125591Y-32283D02*
Y-30951D01*
X126257Y-30284D01*
X126924Y-30951D01*
Y-32283D01*
Y-31284D01*
X125591D01*
X64173Y-42520D02*
Y-41187D01*
X64840Y-40520D01*
X65506Y-41187D01*
Y-42520D01*
Y-41520D01*
X64173D01*
X101181Y-18504D02*
Y-17171D01*
X101848Y-16505D01*
X102514Y-17171D01*
Y-18504D01*
Y-17504D01*
X101181D01*
X101575Y-42126D02*
Y-40793D01*
X102241Y-40127D01*
X102908Y-40793D01*
Y-42126D01*
Y-41126D01*
X101575D01*
X670079Y-9449D02*
Y-8116D01*
X670745Y-7450D01*
X671412Y-8116D01*
Y-9449D01*
Y-8449D01*
X670079D01*
X673228Y-29528D02*
Y-28195D01*
X673895Y-27528D01*
X674561Y-28195D01*
Y-29528D01*
Y-28528D01*
X673228D01*
X671654Y-62598D02*
Y-61265D01*
X672320Y-60599D01*
X672986Y-61265D01*
Y-62598D01*
Y-61599D01*
X671654D01*
Y-41339D02*
Y-40006D01*
X672320Y-39339D01*
X672986Y-40006D01*
Y-41339D01*
Y-40339D01*
X671654D01*
X659449Y-49213D02*
Y-47880D01*
X660115Y-47213D01*
X660782Y-47880D01*
Y-49213D01*
Y-48213D01*
X659449D01*
X596063Y-53937D02*
Y-52604D01*
X596729Y-51938D01*
X597396Y-52604D01*
Y-53937D01*
Y-52937D01*
X596063D01*
X602756Y-39764D02*
Y-38431D01*
X603422Y-37764D01*
X604089Y-38431D01*
Y-39764D01*
Y-38764D01*
X602756D01*
X660236Y-14961D02*
Y-13628D01*
X660903Y-12961D01*
X661569Y-13628D01*
Y-14961D01*
Y-13961D01*
X660236D01*
X614567Y-44882D02*
Y-43549D01*
X615233Y-42882D01*
X615900Y-43549D01*
Y-44882D01*
Y-43882D01*
X614567D01*
X423461Y-178869D02*
Y-177536D01*
X424127Y-176870D01*
X424794Y-177536D01*
Y-178869D01*
Y-177869D01*
X423461D01*
X144871Y-131609D02*
Y-130276D01*
X145537Y-129610D01*
X146204Y-130276D01*
Y-131609D01*
Y-130610D01*
X144871D01*
X120079Y-263386D02*
Y-262053D01*
X120745Y-261386D01*
X121412Y-262053D01*
Y-263386D01*
Y-262386D01*
X120079D01*
X314417Y-228033D02*
Y-226700D01*
X315083Y-226033D01*
X315750Y-226700D01*
Y-228033D01*
Y-227033D01*
X314417D01*
X314623Y-231391D02*
Y-230058D01*
X315290Y-229392D01*
X315956Y-230058D01*
Y-231391D01*
Y-230391D01*
X314623D01*
X325984Y-272441D02*
Y-271108D01*
X326651Y-270442D01*
X327317Y-271108D01*
Y-272441D01*
Y-271441D01*
X325984D01*
X416835Y-196581D02*
Y-195248D01*
X417501Y-194581D01*
X418168Y-195248D01*
Y-196581D01*
Y-195581D01*
X416835D01*
X411811Y-196850D02*
Y-195518D01*
X412477Y-194851D01*
X413144Y-195518D01*
Y-196850D01*
Y-195851D01*
X411811D01*
X570866Y-70472D02*
Y-69139D01*
X571533Y-68473D01*
X572199Y-69139D01*
Y-70472D01*
Y-69473D01*
X570866D01*
Y-72441D02*
Y-71108D01*
X571533Y-70442D01*
X572199Y-71108D01*
Y-72441D01*
Y-71441D01*
X570866D01*
Y-74410D02*
Y-73076D01*
X571533Y-72410D01*
X572199Y-73076D01*
Y-74410D01*
Y-73410D01*
X570866D01*
X574016Y-70472D02*
Y-69139D01*
X574682Y-68473D01*
X575349Y-69139D01*
Y-70472D01*
Y-69473D01*
X574016D01*
Y-72441D02*
Y-71108D01*
X574682Y-70442D01*
X575349Y-71108D01*
Y-72441D01*
Y-71441D01*
X574016D01*
Y-74410D02*
Y-73076D01*
X574682Y-72410D01*
X575349Y-73076D01*
Y-74410D01*
Y-73410D01*
X574016D01*
X350787Y-116929D02*
Y-115596D01*
X351454Y-114930D01*
X352120Y-115596D01*
Y-116929D01*
Y-115929D01*
X350787D01*
X352756Y-116929D02*
Y-115596D01*
X353422Y-114930D01*
X354089Y-115596D01*
Y-116929D01*
Y-115929D01*
X352756D01*
X354724Y-116929D02*
Y-115596D01*
X355391Y-114930D01*
X356057Y-115596D01*
Y-116929D01*
Y-115929D01*
X354724D01*
X350787Y-113779D02*
Y-112447D01*
X351454Y-111780D01*
X352120Y-112447D01*
Y-113779D01*
Y-112780D01*
X350787D01*
X352756Y-113779D02*
Y-112447D01*
X353422Y-111780D01*
X354089Y-112447D01*
Y-113779D01*
Y-112780D01*
X352756D01*
X354724Y-113779D02*
Y-112447D01*
X355391Y-111780D01*
X356057Y-112447D01*
Y-113779D01*
Y-112780D01*
X354724D01*
X379134Y-137795D02*
Y-136462D01*
X379800Y-135796D01*
X380467Y-136462D01*
Y-137795D01*
Y-136796D01*
X379134D01*
X378740Y-127165D02*
Y-125832D01*
X379407Y-125166D01*
X380073Y-125832D01*
Y-127165D01*
Y-126166D01*
X378740D01*
X375532Y-123610D02*
Y-122277D01*
X376199Y-121610D01*
X376865Y-122277D01*
Y-123610D01*
Y-122610D01*
X375532D01*
X314658Y-244775D02*
Y-243442D01*
X315324Y-242775D01*
X315991Y-243442D01*
Y-244775D01*
Y-243775D01*
X314658D01*
X315097Y-235081D02*
Y-233748D01*
X315764Y-233081D01*
X316430Y-233748D01*
Y-235081D01*
Y-234081D01*
X315097D01*
X314503Y-225180D02*
Y-223847D01*
X315169Y-223180D01*
X315835Y-223847D01*
Y-225180D01*
Y-224180D01*
X314503D01*
X288583Y-225590D02*
Y-224258D01*
X289249Y-223591D01*
X289916Y-224258D01*
Y-225590D01*
Y-224591D01*
X288583D01*
X288189Y-228740D02*
Y-227407D01*
X288855Y-226741D01*
X289522Y-227407D01*
Y-228740D01*
Y-227741D01*
X288189D01*
Y-231102D02*
Y-229769D01*
X288855Y-229103D01*
X289522Y-229769D01*
Y-231102D01*
Y-230103D01*
X288189D01*
X288057Y-233478D02*
Y-232145D01*
X288724Y-231479D01*
X289390Y-232145D01*
Y-233478D01*
Y-232478D01*
X288057D01*
X288057Y-245095D02*
Y-243762D01*
X288724Y-243096D01*
X289390Y-243762D01*
Y-245095D01*
Y-244095D01*
X288057D01*
X288189Y-247638D02*
Y-246305D01*
X288855Y-245638D01*
X289522Y-246305D01*
Y-247638D01*
Y-246638D01*
X288189D01*
X287941Y-241819D02*
Y-240486D01*
X288607Y-239820D01*
X289274Y-240486D01*
Y-241819D01*
Y-240819D01*
X287941D01*
X288189Y-235827D02*
Y-234494D01*
X288855Y-233827D01*
X289522Y-234494D01*
Y-235827D01*
Y-234827D01*
X288189D01*
X588976Y-302756D02*
Y-301423D01*
X589643Y-300757D01*
X590309Y-301423D01*
Y-302756D01*
Y-301756D01*
X588976D01*
X579528Y-303150D02*
Y-301817D01*
X580194Y-301150D01*
X580861Y-301817D01*
Y-303150D01*
Y-302150D01*
X579528D01*
X615748Y-305512D02*
Y-304179D01*
X616414Y-303513D01*
X617081Y-304179D01*
Y-305512D01*
Y-304512D01*
X615748D01*
X562598Y-306693D02*
Y-305360D01*
X563265Y-304694D01*
X563931Y-305360D01*
Y-306693D01*
Y-305693D01*
X562598D01*
X377165Y-107283D02*
Y-105951D01*
X377832Y-105284D01*
X378498Y-105951D01*
Y-107283D01*
Y-106284D01*
X377165D01*
X383465Y-107480D02*
Y-106147D01*
X384131Y-105481D01*
X384798Y-106147D01*
Y-107480D01*
Y-106481D01*
X383465D01*
X348211Y-90691D02*
X348611Y-90291D01*
X349011D01*
X348611Y-89891D01*
X349011Y-89491D01*
X348611D01*
X348211Y-89091D01*
X347811Y-89491D01*
X347411D01*
X347811Y-89891D01*
X347411Y-90291D01*
X347811D01*
X348211Y-90691D01*
X357798Y-90763D02*
X358198Y-90363D01*
X358598D01*
X358198Y-89963D01*
X358598Y-89563D01*
X358198D01*
X357798Y-89163D01*
X357398Y-89563D01*
X356998D01*
X357398Y-89963D01*
X356998Y-90363D01*
X357398D01*
X357798Y-90763D01*
X375590Y-127165D02*
Y-125832D01*
X376257Y-125166D01*
X376923Y-125832D01*
Y-127165D01*
Y-126166D01*
X375590D01*
X106299Y-263632D02*
Y-262299D01*
X106966Y-261632D01*
X107632Y-262299D01*
Y-263632D01*
Y-262632D01*
X106299D01*
X380339Y-107321D02*
Y-105988D01*
X381005Y-105321D01*
X381672Y-105988D01*
Y-107321D01*
Y-106321D01*
X380339D01*
X154724Y-389616D02*
Y-388283D01*
X155391Y-387616D01*
X156057Y-388283D01*
Y-389616D01*
Y-388616D01*
X154724D01*
X156693Y-389616D02*
Y-388283D01*
X157359Y-387616D01*
X158026Y-388283D01*
Y-389616D01*
Y-388616D01*
X156693D01*
X158661Y-389616D02*
Y-388283D01*
X159328Y-387616D01*
X159994Y-388283D01*
Y-389616D01*
Y-388616D01*
X158661D01*
X154724Y-386466D02*
Y-385133D01*
X155391Y-384467D01*
X156057Y-385133D01*
Y-386466D01*
Y-385467D01*
X154724D01*
X156693Y-386466D02*
Y-385133D01*
X157359Y-384467D01*
X158026Y-385133D01*
Y-386466D01*
Y-385467D01*
X156693D01*
X158661Y-386466D02*
Y-385133D01*
X159328Y-384467D01*
X159994Y-385133D01*
Y-386466D01*
Y-385467D01*
X158661D01*
X531496Y-262647D02*
Y-261314D01*
X532163Y-260648D01*
X532829Y-261314D01*
Y-262647D01*
Y-261648D01*
X531496D01*
X461811Y-310679D02*
Y-309346D01*
X462477Y-308679D01*
X463144Y-309346D01*
Y-310679D01*
Y-309679D01*
X461811D01*
X450000Y-293750D02*
Y-292417D01*
X450667Y-291750D01*
X451333Y-292417D01*
Y-293750D01*
Y-292750D01*
X450000D01*
X422441Y-293789D02*
Y-292456D01*
X423107Y-291790D01*
X423774Y-292456D01*
Y-293789D01*
Y-292789D01*
X422441D01*
X531496Y-213435D02*
Y-212102D01*
X532163Y-211435D01*
X532829Y-212102D01*
Y-213435D01*
Y-212435D01*
X531496D01*
X338525Y-243567D02*
Y-242234D01*
X339191Y-241567D01*
X339858Y-242234D01*
Y-243567D01*
Y-242567D01*
X338525D01*
X525591Y-233088D02*
Y-231755D01*
X526257Y-231089D01*
X526924Y-231755D01*
Y-233088D01*
Y-232088D01*
X525591D01*
X439697Y-162549D02*
Y-161216D01*
X440363Y-160549D01*
X441030Y-161216D01*
Y-162549D01*
Y-161549D01*
X439697D01*
X343144Y-225173D02*
Y-223840D01*
X343811Y-223174D01*
X344477Y-223840D01*
Y-225173D01*
Y-224173D01*
X343144D01*
X420669Y-157923D02*
Y-156590D01*
X421336Y-155923D01*
X422002Y-156590D01*
Y-157923D01*
Y-156923D01*
X420669D01*
X531496Y-223277D02*
Y-221944D01*
X532163Y-221278D01*
X532829Y-221944D01*
Y-223277D01*
Y-222277D01*
X531496D01*
X338583Y-235236D02*
Y-233903D01*
X339249Y-233237D01*
X339916Y-233903D01*
Y-235236D01*
Y-234237D01*
X338583D01*
X525591Y-242962D02*
Y-241629D01*
X526257Y-240963D01*
X526924Y-241629D01*
Y-242962D01*
Y-241963D01*
X525591D01*
X430150Y-162253D02*
Y-160921D01*
X430816Y-160254D01*
X431483Y-160921D01*
Y-162253D01*
Y-161254D01*
X430150D01*
X343444Y-215373D02*
Y-214040D01*
X344111Y-213374D01*
X344777Y-214040D01*
Y-215373D01*
Y-214373D01*
X343444D01*
X432283Y-293750D02*
Y-292417D01*
X432950Y-291750D01*
X433616Y-292417D01*
Y-293750D01*
Y-292750D01*
X432283D01*
X410528Y-157923D02*
Y-156590D01*
X411194Y-155923D01*
X411861Y-156590D01*
Y-157923D01*
Y-156923D01*
X410528D01*
X342944Y-264473D02*
Y-263140D01*
X343611Y-262474D01*
X344277Y-263140D01*
Y-264473D01*
Y-263474D01*
X342944D01*
X444095Y-293750D02*
Y-292417D01*
X444761Y-291750D01*
X445427Y-292417D01*
Y-293750D01*
Y-292750D01*
X444095D01*
X422835Y-311072D02*
Y-309739D01*
X423501Y-309073D01*
X424168Y-309739D01*
Y-311072D01*
Y-310073D01*
X422835D01*
X531496Y-233088D02*
Y-231755D01*
X532163Y-231089D01*
X532829Y-231755D01*
Y-233088D01*
Y-232088D01*
X531496D01*
X430150Y-157923D02*
Y-156590D01*
X430816Y-155923D01*
X431483Y-156590D01*
Y-157923D01*
Y-156923D01*
X430150D01*
X338444Y-225173D02*
Y-223840D01*
X339111Y-223174D01*
X339777Y-223840D01*
Y-225173D01*
Y-224173D01*
X338444D01*
X402756Y-311072D02*
Y-309739D01*
X403422Y-309073D01*
X404089Y-309739D01*
Y-311072D01*
Y-310073D01*
X402756D01*
X525591Y-253969D02*
Y-252636D01*
X526257Y-251969D01*
X526924Y-252636D01*
Y-253969D01*
Y-252969D01*
X525591D01*
X420079Y-162549D02*
Y-161216D01*
X420745Y-160549D01*
X421412Y-161216D01*
Y-162549D01*
Y-161549D01*
X420079D01*
X343403Y-205651D02*
Y-204318D01*
X344069Y-203651D01*
X344736Y-204318D01*
Y-205651D01*
Y-204651D01*
X343403D01*
X525591Y-203592D02*
Y-202259D01*
X526257Y-201593D01*
X526924Y-202259D01*
Y-203592D01*
Y-202592D01*
X525591D01*
X400295Y-157824D02*
Y-156491D01*
X400962Y-155825D01*
X401628Y-156491D01*
Y-157824D01*
Y-156825D01*
X400295D01*
X343144Y-254773D02*
Y-253440D01*
X343811Y-252774D01*
X344477Y-253440D01*
Y-254773D01*
Y-253773D01*
X343144D01*
X431928Y-311189D02*
Y-309856D01*
X432594Y-309190D01*
X433261Y-309856D01*
Y-311189D01*
Y-310190D01*
X431928D01*
X531496Y-242962D02*
Y-241629D01*
X532163Y-240963D01*
X532829Y-241629D01*
Y-242962D01*
Y-241963D01*
X531496D01*
X338844Y-215273D02*
Y-213940D01*
X339511Y-213274D01*
X340177Y-213940D01*
Y-215273D01*
Y-214274D01*
X338844D01*
X402362Y-293750D02*
Y-292417D01*
X403029Y-291750D01*
X403695Y-292417D01*
Y-293750D01*
Y-292750D01*
X402362D01*
X525591Y-262647D02*
Y-261314D01*
X526257Y-260648D01*
X526924Y-261314D01*
Y-262647D01*
Y-261648D01*
X525591D01*
X410913Y-162758D02*
Y-161425D01*
X411580Y-160758D01*
X412246Y-161425D01*
Y-162758D01*
Y-161758D01*
X410913D01*
X338444Y-264473D02*
Y-263140D01*
X339111Y-262474D01*
X339777Y-263140D01*
Y-264473D01*
Y-263474D01*
X338444D01*
X456299Y-293750D02*
Y-292417D01*
X456966Y-291750D01*
X457632Y-292417D01*
Y-293750D01*
Y-292750D01*
X456299D01*
X437795Y-293750D02*
Y-292417D01*
X438462Y-291750D01*
X439128Y-292417D01*
Y-293750D01*
Y-292750D01*
X437795D01*
X525591Y-213435D02*
Y-212102D01*
X526257Y-211435D01*
X526924Y-212102D01*
Y-213435D01*
Y-212435D01*
X525591D01*
X459319Y-162510D02*
Y-161178D01*
X459985Y-160511D01*
X460652Y-161178D01*
Y-162510D01*
Y-161511D01*
X459319D01*
Y-157922D02*
Y-156589D01*
X459985Y-155923D01*
X460652Y-156589D01*
Y-157922D01*
Y-156922D01*
X459319D01*
X342744Y-243747D02*
Y-242414D01*
X343411Y-241748D01*
X344077Y-242414D01*
Y-243747D01*
Y-242748D01*
X342744D01*
X412598Y-311072D02*
Y-309739D01*
X413265Y-309073D01*
X413931Y-309739D01*
Y-311072D01*
Y-310073D01*
X412598D01*
X531496Y-253969D02*
Y-252636D01*
X532163Y-251969D01*
X532829Y-252636D01*
Y-253969D01*
Y-252969D01*
X531496D01*
X449803Y-157923D02*
Y-156590D01*
X450470Y-155923D01*
X451136Y-156590D01*
Y-157923D01*
Y-156923D01*
X449803D01*
X338744Y-205473D02*
Y-204140D01*
X339411Y-203474D01*
X340077Y-204140D01*
Y-205473D01*
Y-204474D01*
X338744D01*
X531496Y-203592D02*
Y-202259D01*
X532163Y-201593D01*
X532829Y-202259D01*
Y-203592D01*
Y-202592D01*
X531496D01*
X401279Y-162509D02*
Y-161176D01*
X401946Y-160510D01*
X402612Y-161176D01*
Y-162509D01*
Y-161510D01*
X401279D01*
X439961Y-157923D02*
Y-156590D01*
X440627Y-155923D01*
X441293Y-156590D01*
Y-157923D01*
Y-156923D01*
X439961D01*
X338444Y-254773D02*
Y-253440D01*
X339111Y-252774D01*
X339777Y-253440D01*
Y-254773D01*
Y-253773D01*
X338444D01*
X461417Y-293750D02*
Y-292417D01*
X462084Y-291750D01*
X462750Y-292417D01*
Y-293750D01*
Y-292750D01*
X461417D01*
X525591Y-223277D02*
Y-221944D01*
X526257Y-221278D01*
X526924Y-221944D01*
Y-223277D01*
Y-222277D01*
X525591D01*
X449508Y-162549D02*
Y-161216D01*
X450174Y-160549D01*
X450841Y-161216D01*
Y-162549D01*
Y-161549D01*
X449508D01*
X343504Y-235236D02*
Y-233903D01*
X344170Y-233237D01*
X344837Y-233903D01*
Y-235236D01*
Y-234237D01*
X343504D01*
X412205Y-293750D02*
Y-292417D01*
X412871Y-291750D01*
X413538Y-292417D01*
Y-293750D01*
Y-292750D01*
X412205D01*
X639750Y-314581D02*
Y-313248D01*
X640416Y-312582D01*
X641083Y-313248D01*
Y-314581D01*
Y-313581D01*
X639750D01*
X658647Y-314581D02*
Y-313248D01*
X659314Y-312582D01*
X659980Y-313248D01*
Y-314581D01*
Y-313581D01*
X658647D01*
X509405Y-345138D02*
Y-343805D01*
X510071Y-343139D01*
X510738Y-343805D01*
Y-345138D01*
Y-344138D01*
X509405D01*
X509011Y-330177D02*
Y-328844D01*
X509678Y-328178D01*
X510344Y-328844D01*
Y-330177D01*
Y-329177D01*
X509011D01*
X56441Y-143600D02*
Y-142267D01*
X57107Y-141601D01*
X57774Y-142267D01*
Y-143600D01*
Y-142600D01*
X56441D01*
Y-151600D02*
Y-150267D01*
X57107Y-149601D01*
X57774Y-150267D01*
Y-151600D01*
Y-150600D01*
X56441D01*
Y-191600D02*
Y-190267D01*
X57107Y-189601D01*
X57774Y-190267D01*
Y-191600D01*
Y-190600D01*
X56441D01*
Y-199600D02*
Y-198267D01*
X57107Y-197601D01*
X57774Y-198267D01*
Y-199600D01*
Y-198600D01*
X56441D01*
Y-215600D02*
Y-214267D01*
X57107Y-213601D01*
X57774Y-214267D01*
Y-215600D01*
Y-214600D01*
X56441D01*
Y-223600D02*
Y-222267D01*
X57107Y-221601D01*
X57774Y-222267D01*
Y-223600D01*
Y-222600D01*
X56441D01*
Y-231600D02*
Y-230267D01*
X57107Y-229601D01*
X57774Y-230267D01*
Y-231600D01*
Y-230600D01*
X56441D01*
Y-247600D02*
Y-246267D01*
X57107Y-245601D01*
X57774Y-246267D01*
Y-247600D01*
Y-246600D01*
X56441D01*
Y-255600D02*
Y-254267D01*
X57107Y-253601D01*
X57774Y-254267D01*
Y-255600D01*
Y-254600D01*
X56441D01*
Y-271600D02*
Y-270267D01*
X57107Y-269601D01*
X57774Y-270267D01*
Y-271600D01*
Y-270600D01*
X56441D01*
Y-279600D02*
Y-278267D01*
X57107Y-277601D01*
X57774Y-278267D01*
Y-279600D01*
Y-278600D01*
X56441D01*
Y-287600D02*
Y-286267D01*
X57107Y-285601D01*
X57774Y-286267D01*
Y-287600D01*
Y-286600D01*
X56441D01*
Y-303600D02*
Y-302267D01*
X57107Y-301601D01*
X57774Y-302267D01*
Y-303600D01*
Y-302600D01*
X56441D01*
Y-311600D02*
Y-310267D01*
X57107Y-309601D01*
X57774Y-310267D01*
Y-311600D01*
Y-310600D01*
X56441D01*
Y-327600D02*
Y-326267D01*
X57107Y-325601D01*
X57774Y-326267D01*
Y-327600D01*
Y-326600D01*
X56441D01*
Y-335600D02*
Y-334267D01*
X57107Y-333601D01*
X57774Y-334267D01*
Y-335600D01*
Y-334600D01*
X56441D01*
Y-343600D02*
Y-342267D01*
X57107Y-341601D01*
X57774Y-342267D01*
Y-343600D01*
Y-342600D01*
X56441D01*
Y-351600D02*
Y-350267D01*
X57107Y-349601D01*
X57774Y-350267D01*
Y-351600D01*
Y-350600D01*
X56441D01*
X54441Y-139600D02*
Y-138267D01*
X55107Y-137601D01*
X55774Y-138267D01*
Y-139600D01*
Y-138600D01*
X54441D01*
X52441Y-143600D02*
Y-142267D01*
X53107Y-141601D01*
X53774Y-142267D01*
Y-143600D01*
Y-142600D01*
X52441D01*
X54441Y-147600D02*
Y-146267D01*
X55107Y-145601D01*
X55774Y-146267D01*
Y-147600D01*
Y-146600D01*
X54441D01*
X52441Y-151600D02*
Y-150267D01*
X53107Y-149601D01*
X53774Y-150267D01*
Y-151600D01*
Y-150600D01*
X52441D01*
Y-191600D02*
Y-190267D01*
X53107Y-189601D01*
X53774Y-190267D01*
Y-191600D01*
Y-190600D01*
X52441D01*
X54441Y-195600D02*
Y-194267D01*
X55107Y-193601D01*
X55774Y-194267D01*
Y-195600D01*
Y-194600D01*
X54441D01*
X52441Y-199600D02*
Y-198267D01*
X53107Y-197601D01*
X53774Y-198267D01*
Y-199600D01*
Y-198600D01*
X52441D01*
X54441Y-203600D02*
Y-202267D01*
X55107Y-201601D01*
X55774Y-202267D01*
Y-203600D01*
Y-202600D01*
X54441D01*
X52441Y-215600D02*
Y-214267D01*
X53107Y-213601D01*
X53774Y-214267D01*
Y-215600D01*
Y-214600D01*
X52441D01*
X54441Y-219600D02*
Y-218267D01*
X55107Y-217601D01*
X55774Y-218267D01*
Y-219600D01*
Y-218600D01*
X54441D01*
X52441Y-223600D02*
Y-222267D01*
X53107Y-221601D01*
X53774Y-222267D01*
Y-223600D01*
Y-222600D01*
X52441D01*
X54441Y-227600D02*
Y-226267D01*
X55107Y-225601D01*
X55774Y-226267D01*
Y-227600D01*
Y-226600D01*
X54441D01*
X52441Y-231600D02*
Y-230267D01*
X53107Y-229601D01*
X53774Y-230267D01*
Y-231600D01*
Y-230600D01*
X52441D01*
X54441Y-235600D02*
Y-234267D01*
X55107Y-233601D01*
X55774Y-234267D01*
Y-235600D01*
Y-234600D01*
X54441D01*
Y-243600D02*
Y-242267D01*
X55107Y-241601D01*
X55774Y-242267D01*
Y-243600D01*
Y-242600D01*
X54441D01*
X52441Y-247600D02*
Y-246267D01*
X53107Y-245601D01*
X53774Y-246267D01*
Y-247600D01*
Y-246600D01*
X52441D01*
X54441Y-251600D02*
Y-250267D01*
X55107Y-249601D01*
X55774Y-250267D01*
Y-251600D01*
Y-250600D01*
X54441D01*
X52441Y-255600D02*
Y-254267D01*
X53107Y-253601D01*
X53774Y-254267D01*
Y-255600D01*
Y-254600D01*
X52441D01*
X54441Y-267600D02*
Y-266267D01*
X55107Y-265601D01*
X55774Y-266267D01*
Y-267600D01*
Y-266600D01*
X54441D01*
X52441Y-271600D02*
Y-270267D01*
X53107Y-269601D01*
X53774Y-270267D01*
Y-271600D01*
Y-270600D01*
X52441D01*
X54441Y-275600D02*
Y-274267D01*
X55107Y-273601D01*
X55774Y-274267D01*
Y-275600D01*
Y-274600D01*
X54441D01*
X52441Y-279600D02*
Y-278267D01*
X53107Y-277601D01*
X53774Y-278267D01*
Y-279600D01*
Y-278600D01*
X52441D01*
Y-287600D02*
Y-286267D01*
X53107Y-285601D01*
X53774Y-286267D01*
Y-287600D01*
Y-286600D01*
X52441D01*
X54441Y-291600D02*
Y-290267D01*
X55107Y-289601D01*
X55774Y-290267D01*
Y-291600D01*
Y-290600D01*
X54441D01*
Y-299600D02*
Y-298267D01*
X55107Y-297601D01*
X55774Y-298267D01*
Y-299600D01*
Y-298600D01*
X54441D01*
X52441Y-303600D02*
Y-302267D01*
X53107Y-301601D01*
X53774Y-302267D01*
Y-303600D01*
Y-302600D01*
X52441D01*
X54441Y-307600D02*
Y-306267D01*
X55107Y-305601D01*
X55774Y-306267D01*
Y-307600D01*
Y-306600D01*
X54441D01*
X52441Y-311600D02*
Y-310267D01*
X53107Y-309601D01*
X53774Y-310267D01*
Y-311600D01*
Y-310600D01*
X52441D01*
X54441Y-323600D02*
Y-322267D01*
X55107Y-321601D01*
X55774Y-322267D01*
Y-323600D01*
Y-322600D01*
X54441D01*
X52441Y-327600D02*
Y-326267D01*
X53107Y-325601D01*
X53774Y-326267D01*
Y-327600D01*
Y-326600D01*
X52441D01*
X54441Y-331600D02*
Y-330267D01*
X55107Y-329601D01*
X55774Y-330267D01*
Y-331600D01*
Y-330600D01*
X54441D01*
X52441Y-335600D02*
Y-334267D01*
X53107Y-333601D01*
X53774Y-334267D01*
Y-335600D01*
Y-334600D01*
X52441D01*
X54441Y-339600D02*
Y-338267D01*
X55107Y-337601D01*
X55774Y-338267D01*
Y-339600D01*
Y-338600D01*
X54441D01*
X52441Y-343600D02*
Y-342267D01*
X53107Y-341601D01*
X53774Y-342267D01*
Y-343600D01*
Y-342600D01*
X52441D01*
Y-351600D02*
Y-350267D01*
X53107Y-349601D01*
X53774Y-350267D01*
Y-351600D01*
Y-350600D01*
X52441D01*
X50441Y-139600D02*
Y-138267D01*
X51107Y-137601D01*
X51774Y-138267D01*
Y-139600D01*
Y-138600D01*
X50441D01*
X48441Y-143600D02*
Y-142267D01*
X49107Y-141601D01*
X49774Y-142267D01*
Y-143600D01*
Y-142600D01*
X48441D01*
X50441Y-195600D02*
Y-194267D01*
X51107Y-193601D01*
X51774Y-194267D01*
Y-195600D01*
Y-194600D01*
X50441D01*
X48441Y-199600D02*
Y-198267D01*
X49107Y-197601D01*
X49774Y-198267D01*
Y-199600D01*
Y-198600D01*
X48441D01*
Y-223600D02*
Y-222267D01*
X49107Y-221601D01*
X49774Y-222267D01*
Y-223600D01*
Y-222600D01*
X48441D01*
X50441Y-227600D02*
Y-226267D01*
X51107Y-225601D01*
X51774Y-226267D01*
Y-227600D01*
Y-226600D01*
X50441D01*
X48441Y-231600D02*
Y-230267D01*
X49107Y-229601D01*
X49774Y-230267D01*
Y-231600D01*
Y-230600D01*
X48441D01*
X50441Y-235600D02*
Y-234267D01*
X51107Y-233601D01*
X51774Y-234267D01*
Y-235600D01*
Y-234600D01*
X50441D01*
Y-243600D02*
Y-242267D01*
X51107Y-241601D01*
X51774Y-242267D01*
Y-243600D01*
Y-242600D01*
X50441D01*
X48441Y-247600D02*
Y-246267D01*
X49107Y-245601D01*
X49774Y-246267D01*
Y-247600D01*
Y-246600D01*
X48441D01*
X50441Y-251600D02*
Y-250267D01*
X51107Y-249601D01*
X51774Y-250267D01*
Y-251600D01*
Y-250600D01*
X50441D01*
Y-275600D02*
Y-274267D01*
X51107Y-273601D01*
X51774Y-274267D01*
Y-275600D01*
Y-274600D01*
X50441D01*
X48441Y-279600D02*
Y-278267D01*
X49107Y-277601D01*
X49774Y-278267D01*
Y-279600D01*
Y-278600D01*
X48441D01*
Y-287600D02*
Y-286267D01*
X49107Y-285601D01*
X49774Y-286267D01*
Y-287600D01*
Y-286600D01*
X48441D01*
X50441Y-291600D02*
Y-290267D01*
X51107Y-289601D01*
X51774Y-290267D01*
Y-291600D01*
Y-290600D01*
X50441D01*
Y-299600D02*
Y-298267D01*
X51107Y-297601D01*
X51774Y-298267D01*
Y-299600D01*
Y-298600D01*
X50441D01*
X48441Y-303600D02*
Y-302267D01*
X49107Y-301601D01*
X49774Y-302267D01*
Y-303600D01*
Y-302600D01*
X48441D01*
X50441Y-331600D02*
Y-330267D01*
X51107Y-329601D01*
X51774Y-330267D01*
Y-331600D01*
Y-330600D01*
X50441D01*
X48441Y-335600D02*
Y-334267D01*
X49107Y-333601D01*
X49774Y-334267D01*
Y-335600D01*
Y-334600D01*
X48441D01*
X50441Y-339600D02*
Y-338267D01*
X51107Y-337601D01*
X51774Y-338267D01*
Y-339600D01*
Y-338600D01*
X50441D01*
X48441Y-343600D02*
Y-342267D01*
X49107Y-341601D01*
X49774Y-342267D01*
Y-343600D01*
Y-342600D01*
X48441D01*
Y-351600D02*
Y-350267D01*
X49107Y-349601D01*
X49774Y-350267D01*
Y-351600D01*
Y-350600D01*
X48441D01*
X46441Y-139600D02*
Y-138267D01*
X47107Y-137601D01*
X47774Y-138267D01*
Y-139600D01*
Y-138600D01*
X46441D01*
X44441Y-143600D02*
Y-142267D01*
X45107Y-141601D01*
X45774Y-142267D01*
Y-143600D01*
Y-142600D01*
X44441D01*
X46441Y-227600D02*
Y-226267D01*
X47107Y-225601D01*
X47774Y-226267D01*
Y-227600D01*
Y-226600D01*
X46441D01*
X44441Y-231600D02*
Y-230267D01*
X45107Y-229601D01*
X45774Y-230267D01*
Y-231600D01*
Y-230600D01*
X44441D01*
X46441Y-235600D02*
Y-234267D01*
X47107Y-233601D01*
X47774Y-234267D01*
Y-235600D01*
Y-234600D01*
X46441D01*
Y-243600D02*
Y-242267D01*
X47107Y-241601D01*
X47774Y-242267D01*
Y-243600D01*
Y-242600D01*
X46441D01*
X44441Y-247600D02*
Y-246267D01*
X45107Y-245601D01*
X45774Y-246267D01*
Y-247600D01*
Y-246600D01*
X44441D01*
Y-279600D02*
Y-278267D01*
X45107Y-277601D01*
X45774Y-278267D01*
Y-279600D01*
Y-278600D01*
X44441D01*
Y-287600D02*
Y-286267D01*
X45107Y-285601D01*
X45774Y-286267D01*
Y-287600D01*
Y-286600D01*
X44441D01*
X46441Y-291600D02*
Y-290267D01*
X47107Y-289601D01*
X47774Y-290267D01*
Y-291600D01*
Y-290600D01*
X46441D01*
Y-299600D02*
Y-298267D01*
X47107Y-297601D01*
X47774Y-298267D01*
Y-299600D01*
Y-298600D01*
X46441D01*
Y-331600D02*
Y-330267D01*
X47107Y-329601D01*
X47774Y-330267D01*
Y-331600D01*
Y-330600D01*
X46441D01*
X44441Y-335600D02*
Y-334267D01*
X45107Y-333601D01*
X45774Y-334267D01*
Y-335600D01*
Y-334600D01*
X44441D01*
X46441Y-339600D02*
Y-338267D01*
X47107Y-337601D01*
X47774Y-338267D01*
Y-339600D01*
Y-338600D01*
X46441D01*
X44441Y-343600D02*
Y-342267D01*
X45107Y-341601D01*
X45774Y-342267D01*
Y-343600D01*
Y-342600D01*
X44441D01*
Y-351600D02*
Y-350267D01*
X45107Y-349601D01*
X45774Y-350267D01*
Y-351600D01*
Y-350600D01*
X44441D01*
X42441Y-139600D02*
Y-138267D01*
X43107Y-137601D01*
X43774Y-138267D01*
Y-139600D01*
Y-138600D01*
X42441D01*
X40441Y-143600D02*
Y-142267D01*
X41107Y-141601D01*
X41774Y-142267D01*
Y-143600D01*
Y-142600D01*
X40441D01*
Y-223600D02*
Y-222267D01*
X41107Y-221601D01*
X41774Y-222267D01*
Y-223600D01*
Y-222600D01*
X40441D01*
X42441Y-227600D02*
Y-226267D01*
X43107Y-225601D01*
X43774Y-226267D01*
Y-227600D01*
Y-226600D01*
X42441D01*
X40441Y-231600D02*
Y-230267D01*
X41107Y-229601D01*
X41774Y-230267D01*
Y-231600D01*
Y-230600D01*
X40441D01*
X42441Y-235600D02*
Y-234267D01*
X43107Y-233601D01*
X43774Y-234267D01*
Y-235600D01*
Y-234600D01*
X42441D01*
Y-243600D02*
Y-242267D01*
X43107Y-241601D01*
X43774Y-242267D01*
Y-243600D01*
Y-242600D01*
X42441D01*
X40441Y-247600D02*
Y-246267D01*
X41107Y-245601D01*
X41774Y-246267D01*
Y-247600D01*
Y-246600D01*
X40441D01*
X42441Y-299600D02*
Y-298267D01*
X43107Y-297601D01*
X43774Y-298267D01*
Y-299600D01*
Y-298600D01*
X42441D01*
Y-331600D02*
Y-330267D01*
X43107Y-329601D01*
X43774Y-330267D01*
Y-331600D01*
Y-330600D01*
X42441D01*
X40441Y-335600D02*
Y-334267D01*
X41107Y-333601D01*
X41774Y-334267D01*
Y-335600D01*
Y-334600D01*
X40441D01*
X42441Y-339600D02*
Y-338267D01*
X43107Y-337601D01*
X43774Y-338267D01*
Y-339600D01*
Y-338600D01*
X42441D01*
X40441Y-343600D02*
Y-342267D01*
X41107Y-341601D01*
X41774Y-342267D01*
Y-343600D01*
Y-342600D01*
X40441D01*
Y-351600D02*
Y-350267D01*
X41107Y-349601D01*
X41774Y-350267D01*
Y-351600D01*
Y-350600D01*
X40441D01*
X38441Y-139600D02*
Y-138267D01*
X39107Y-137601D01*
X39774Y-138267D01*
Y-139600D01*
Y-138600D01*
X38441D01*
X36441Y-143600D02*
Y-142267D01*
X37107Y-141601D01*
X37774Y-142267D01*
Y-143600D01*
Y-142600D01*
X36441D01*
Y-151600D02*
Y-150267D01*
X37107Y-149601D01*
X37774Y-150267D01*
Y-151600D01*
Y-150600D01*
X36441D01*
Y-215600D02*
Y-214267D01*
X37107Y-213601D01*
X37774Y-214267D01*
Y-215600D01*
Y-214600D01*
X36441D01*
Y-223600D02*
Y-222267D01*
X37107Y-221601D01*
X37774Y-222267D01*
Y-223600D01*
Y-222600D01*
X36441D01*
X38441Y-227600D02*
Y-226267D01*
X39107Y-225601D01*
X39774Y-226267D01*
Y-227600D01*
Y-226600D01*
X38441D01*
X36441Y-231600D02*
Y-230267D01*
X37107Y-229601D01*
X37774Y-230267D01*
Y-231600D01*
Y-230600D01*
X36441D01*
X38441Y-235600D02*
Y-234267D01*
X39107Y-233601D01*
X39774Y-234267D01*
Y-235600D01*
Y-234600D01*
X38441D01*
Y-243600D02*
Y-242267D01*
X39107Y-241601D01*
X39774Y-242267D01*
Y-243600D01*
Y-242600D01*
X38441D01*
X36441Y-247600D02*
Y-246267D01*
X37107Y-245601D01*
X37774Y-246267D01*
Y-247600D01*
Y-246600D01*
X36441D01*
X38441Y-251600D02*
Y-250267D01*
X39107Y-249601D01*
X39774Y-250267D01*
Y-251600D01*
Y-250600D01*
X38441D01*
X36441Y-255600D02*
Y-254267D01*
X37107Y-253601D01*
X37774Y-254267D01*
Y-255600D01*
Y-254600D01*
X36441D01*
Y-327600D02*
Y-326267D01*
X37107Y-325601D01*
X37774Y-326267D01*
Y-327600D01*
Y-326600D01*
X36441D01*
X38441Y-331600D02*
Y-330267D01*
X39107Y-329601D01*
X39774Y-330267D01*
Y-331600D01*
Y-330600D01*
X38441D01*
X36441Y-335600D02*
Y-334267D01*
X37107Y-333601D01*
X37774Y-334267D01*
Y-335600D01*
Y-334600D01*
X36441D01*
X38441Y-339600D02*
Y-338267D01*
X39107Y-337601D01*
X39774Y-338267D01*
Y-339600D01*
Y-338600D01*
X38441D01*
X36441Y-343600D02*
Y-342267D01*
X37107Y-341601D01*
X37774Y-342267D01*
Y-343600D01*
Y-342600D01*
X36441D01*
Y-351600D02*
Y-350267D01*
X37107Y-349601D01*
X37774Y-350267D01*
Y-351600D01*
Y-350600D01*
X36441D01*
X34441Y-139600D02*
Y-138267D01*
X35107Y-137601D01*
X35774Y-138267D01*
Y-139600D01*
Y-138600D01*
X34441D01*
X32441Y-143600D02*
Y-142267D01*
X33107Y-141601D01*
X33774Y-142267D01*
Y-143600D01*
Y-142600D01*
X32441D01*
X34441Y-147600D02*
Y-146267D01*
X35107Y-145601D01*
X35774Y-146267D01*
Y-147600D01*
Y-146600D01*
X34441D01*
X32441Y-151600D02*
Y-150267D01*
X33107Y-149601D01*
X33774Y-150267D01*
Y-151600D01*
Y-150600D01*
X32441D01*
X34441Y-163600D02*
Y-162267D01*
X35107Y-161601D01*
X35774Y-162267D01*
Y-163600D01*
Y-162600D01*
X34441D01*
Y-219600D02*
Y-218267D01*
X35107Y-217601D01*
X35774Y-218267D01*
Y-219600D01*
Y-218600D01*
X34441D01*
Y-227600D02*
Y-226267D01*
X35107Y-225601D01*
X35774Y-226267D01*
Y-227600D01*
Y-226600D01*
X34441D01*
Y-235600D02*
Y-234267D01*
X35107Y-233601D01*
X35774Y-234267D01*
Y-235600D01*
Y-234600D01*
X34441D01*
Y-243600D02*
Y-242267D01*
X35107Y-241601D01*
X35774Y-242267D01*
Y-243600D01*
Y-242600D01*
X34441D01*
Y-251600D02*
Y-250267D01*
X35107Y-249601D01*
X35774Y-250267D01*
Y-251600D01*
Y-250600D01*
X34441D01*
Y-267600D02*
Y-266267D01*
X35107Y-265601D01*
X35774Y-266267D01*
Y-267600D01*
Y-266600D01*
X34441D01*
Y-275600D02*
Y-274267D01*
X35107Y-273601D01*
X35774Y-274267D01*
Y-275600D01*
Y-274600D01*
X34441D01*
Y-299600D02*
Y-298267D01*
X35107Y-297601D01*
X35774Y-298267D01*
Y-299600D01*
Y-298600D01*
X34441D01*
Y-307600D02*
Y-306267D01*
X35107Y-305601D01*
X35774Y-306267D01*
Y-307600D01*
Y-306600D01*
X34441D01*
Y-323600D02*
Y-322267D01*
X35107Y-321601D01*
X35774Y-322267D01*
Y-323600D01*
Y-322600D01*
X34441D01*
X32441Y-327600D02*
Y-326267D01*
X33107Y-325601D01*
X33774Y-326267D01*
Y-327600D01*
Y-326600D01*
X32441D01*
X34441Y-331600D02*
Y-330267D01*
X35107Y-329601D01*
X35774Y-330267D01*
Y-331600D01*
Y-330600D01*
X34441D01*
X32441Y-335600D02*
Y-334267D01*
X33107Y-333601D01*
X33774Y-334267D01*
Y-335600D01*
Y-334600D01*
X32441D01*
X34441Y-339600D02*
Y-338267D01*
X35107Y-337601D01*
X35774Y-338267D01*
Y-339600D01*
Y-338600D01*
X34441D01*
X32441Y-343600D02*
Y-342267D01*
X33107Y-341601D01*
X33774Y-342267D01*
Y-343600D01*
Y-342600D01*
X32441D01*
Y-351600D02*
Y-350267D01*
X33107Y-349601D01*
X33774Y-350267D01*
Y-351600D01*
Y-350600D01*
X32441D01*
X30441Y-139600D02*
Y-138267D01*
X31107Y-137601D01*
X31774Y-138267D01*
Y-139600D01*
Y-138600D01*
X30441D01*
X28441Y-143600D02*
Y-142267D01*
X29107Y-141601D01*
X29774Y-142267D01*
Y-143600D01*
Y-142600D01*
X28441D01*
X30441Y-147600D02*
Y-146267D01*
X31107Y-145601D01*
X31774Y-146267D01*
Y-147600D01*
Y-146600D01*
X30441D01*
X28441Y-151600D02*
Y-150267D01*
X29107Y-149601D01*
X29774Y-150267D01*
Y-151600D01*
Y-150600D01*
X28441D01*
X30441Y-163600D02*
Y-162267D01*
X31107Y-161601D01*
X31774Y-162267D01*
Y-163600D01*
Y-162600D01*
X30441D01*
X28441Y-167600D02*
Y-166267D01*
X29107Y-165601D01*
X29774Y-166267D01*
Y-167600D01*
Y-166600D01*
X28441D01*
Y-327600D02*
Y-326267D01*
X29107Y-325601D01*
X29774Y-326267D01*
Y-327600D01*
Y-326600D01*
X28441D01*
X30441Y-331600D02*
Y-330267D01*
X31107Y-329601D01*
X31774Y-330267D01*
Y-331600D01*
Y-330600D01*
X30441D01*
X28441Y-335600D02*
Y-334267D01*
X29107Y-333601D01*
X29774Y-334267D01*
Y-335600D01*
Y-334600D01*
X28441D01*
X30441Y-339600D02*
Y-338267D01*
X31107Y-337601D01*
X31774Y-338267D01*
Y-339600D01*
Y-338600D01*
X30441D01*
X28441Y-343600D02*
Y-342267D01*
X29107Y-341601D01*
X29774Y-342267D01*
Y-343600D01*
Y-342600D01*
X28441D01*
Y-351600D02*
Y-350267D01*
X29107Y-349601D01*
X29774Y-350267D01*
Y-351600D01*
Y-350600D01*
X28441D01*
X26441Y-139600D02*
Y-138267D01*
X27107Y-137601D01*
X27774Y-138267D01*
Y-139600D01*
Y-138600D01*
X26441D01*
X24441Y-143600D02*
Y-142267D01*
X25107Y-141601D01*
X25774Y-142267D01*
Y-143600D01*
Y-142600D01*
X24441D01*
X26441Y-147600D02*
Y-146267D01*
X27107Y-145601D01*
X27774Y-146267D01*
Y-147600D01*
Y-146600D01*
X26441D01*
X24441Y-151600D02*
Y-150267D01*
X25107Y-149601D01*
X25774Y-150267D01*
Y-151600D01*
Y-150600D01*
X24441D01*
X26441Y-163600D02*
Y-162267D01*
X27107Y-161601D01*
X27774Y-162267D01*
Y-163600D01*
Y-162600D01*
X26441D01*
X24441Y-167600D02*
Y-166267D01*
X25107Y-165601D01*
X25774Y-166267D01*
Y-167600D01*
Y-166600D01*
X24441D01*
Y-191600D02*
Y-190267D01*
X25107Y-189601D01*
X25774Y-190267D01*
Y-191600D01*
Y-190600D01*
X24441D01*
X26441Y-195600D02*
Y-194267D01*
X27107Y-193601D01*
X27774Y-194267D01*
Y-195600D01*
Y-194600D01*
X26441D01*
X24441Y-287600D02*
Y-286267D01*
X25107Y-285601D01*
X25774Y-286267D01*
Y-287600D01*
Y-286600D01*
X24441D01*
X26441Y-299600D02*
Y-298267D01*
X27107Y-297601D01*
X27774Y-298267D01*
Y-299600D01*
Y-298600D01*
X26441D01*
X24441Y-303600D02*
Y-302267D01*
X25107Y-301601D01*
X25774Y-302267D01*
Y-303600D01*
Y-302600D01*
X24441D01*
X26441Y-307600D02*
Y-306267D01*
X27107Y-305601D01*
X27774Y-306267D01*
Y-307600D01*
Y-306600D01*
X26441D01*
X24441Y-311600D02*
Y-310267D01*
X25107Y-309601D01*
X25774Y-310267D01*
Y-311600D01*
Y-310600D01*
X24441D01*
X26441Y-331600D02*
Y-330267D01*
X27107Y-329601D01*
X27774Y-330267D01*
Y-331600D01*
Y-330600D01*
X26441D01*
X24441Y-335600D02*
Y-334267D01*
X25107Y-333601D01*
X25774Y-334267D01*
Y-335600D01*
Y-334600D01*
X24441D01*
X26441Y-339600D02*
Y-338267D01*
X27107Y-337601D01*
X27774Y-338267D01*
Y-339600D01*
Y-338600D01*
X26441D01*
X24441Y-343600D02*
Y-342267D01*
X25107Y-341601D01*
X25774Y-342267D01*
Y-343600D01*
Y-342600D01*
X24441D01*
Y-351600D02*
Y-350267D01*
X25107Y-349601D01*
X25774Y-350267D01*
Y-351600D01*
Y-350600D01*
X24441D01*
X22441Y-139600D02*
Y-138267D01*
X23107Y-137601D01*
X23774Y-138267D01*
Y-139600D01*
Y-138600D01*
X22441D01*
X20441Y-143600D02*
Y-142267D01*
X21107Y-141601D01*
X21774Y-142267D01*
Y-143600D01*
Y-142600D01*
X20441D01*
X22441Y-147600D02*
Y-146267D01*
X23107Y-145601D01*
X23774Y-146267D01*
Y-147600D01*
Y-146600D01*
X22441D01*
X20441Y-151600D02*
Y-150267D01*
X21107Y-149601D01*
X21774Y-150267D01*
Y-151600D01*
Y-150600D01*
X20441D01*
X22441Y-163600D02*
Y-162267D01*
X23107Y-161601D01*
X23774Y-162267D01*
Y-163600D01*
Y-162600D01*
X22441D01*
X20441Y-167600D02*
Y-166267D01*
X21107Y-165601D01*
X21774Y-166267D01*
Y-167600D01*
Y-166600D01*
X20441D01*
X22441Y-171600D02*
Y-170267D01*
X23107Y-169601D01*
X23774Y-170267D01*
Y-171600D01*
Y-170600D01*
X22441D01*
X20441Y-191600D02*
Y-190267D01*
X21107Y-189601D01*
X21774Y-190267D01*
Y-191600D01*
Y-190600D01*
X20441D01*
X22441Y-195600D02*
Y-194267D01*
X23107Y-193601D01*
X23774Y-194267D01*
Y-195600D01*
Y-194600D01*
X22441D01*
X20441Y-199600D02*
Y-198267D01*
X21107Y-197601D01*
X21774Y-198267D01*
Y-199600D01*
Y-198600D01*
X20441D01*
Y-231600D02*
Y-230267D01*
X21107Y-229601D01*
X21774Y-230267D01*
Y-231600D01*
Y-230600D01*
X20441D01*
X22441Y-235600D02*
Y-234267D01*
X23107Y-233601D01*
X23774Y-234267D01*
Y-235600D01*
Y-234600D01*
X22441D01*
Y-243600D02*
Y-242267D01*
X23107Y-241601D01*
X23774Y-242267D01*
Y-243600D01*
Y-242600D01*
X22441D01*
X20441Y-247600D02*
Y-246267D01*
X21107Y-245601D01*
X21774Y-246267D01*
Y-247600D01*
Y-246600D01*
X20441D01*
X22441Y-251600D02*
Y-250267D01*
X23107Y-249601D01*
X23774Y-250267D01*
Y-251600D01*
Y-250600D01*
X22441D01*
X20441Y-255600D02*
Y-254267D01*
X21107Y-253601D01*
X21774Y-254267D01*
Y-255600D01*
Y-254600D01*
X20441D01*
X22441Y-259600D02*
Y-258267D01*
X23107Y-257601D01*
X23774Y-258267D01*
Y-259600D01*
Y-258600D01*
X22441D01*
Y-267600D02*
Y-266267D01*
X23107Y-265601D01*
X23774Y-266267D01*
Y-267600D01*
Y-266600D01*
X22441D01*
X20441Y-271600D02*
Y-270267D01*
X21107Y-269601D01*
X21774Y-270267D01*
Y-271600D01*
Y-270600D01*
X20441D01*
X22441Y-283600D02*
Y-282267D01*
X23107Y-281601D01*
X23774Y-282267D01*
Y-283600D01*
Y-282600D01*
X22441D01*
X20441Y-287600D02*
Y-286267D01*
X21107Y-285601D01*
X21774Y-286267D01*
Y-287600D01*
Y-286600D01*
X20441D01*
X22441Y-291600D02*
Y-290267D01*
X23107Y-289601D01*
X23774Y-290267D01*
Y-291600D01*
Y-290600D01*
X22441D01*
Y-299600D02*
Y-298267D01*
X23107Y-297601D01*
X23774Y-298267D01*
Y-299600D01*
Y-298600D01*
X22441D01*
X20441Y-303600D02*
Y-302267D01*
X21107Y-301601D01*
X21774Y-302267D01*
Y-303600D01*
Y-302600D01*
X20441D01*
X22441Y-307600D02*
Y-306267D01*
X23107Y-305601D01*
X23774Y-306267D01*
Y-307600D01*
Y-306600D01*
X22441D01*
X20441Y-311600D02*
Y-310267D01*
X21107Y-309601D01*
X21774Y-310267D01*
Y-311600D01*
Y-310600D01*
X20441D01*
X22441Y-323600D02*
Y-322267D01*
X23107Y-321601D01*
X23774Y-322267D01*
Y-323600D01*
Y-322600D01*
X22441D01*
X20441Y-335600D02*
Y-334267D01*
X21107Y-333601D01*
X21774Y-334267D01*
Y-335600D01*
Y-334600D01*
X20441D01*
X22441Y-339600D02*
Y-338267D01*
X23107Y-337601D01*
X23774Y-338267D01*
Y-339600D01*
Y-338600D01*
X22441D01*
X20441Y-343600D02*
Y-342267D01*
X21107Y-341601D01*
X21774Y-342267D01*
Y-343600D01*
Y-342600D01*
X20441D01*
Y-351600D02*
Y-350267D01*
X21107Y-349601D01*
X21774Y-350267D01*
Y-351600D01*
Y-350600D01*
X20441D01*
X18441Y-139600D02*
Y-138267D01*
X19107Y-137601D01*
X19774Y-138267D01*
Y-139600D01*
Y-138600D01*
X18441D01*
X16441Y-143600D02*
Y-142267D01*
X17107Y-141601D01*
X17774Y-142267D01*
Y-143600D01*
Y-142600D01*
X16441D01*
X18441Y-147600D02*
Y-146267D01*
X19107Y-145601D01*
X19774Y-146267D01*
Y-147600D01*
Y-146600D01*
X18441D01*
X16441Y-151600D02*
Y-150267D01*
X17107Y-149601D01*
X17774Y-150267D01*
Y-151600D01*
Y-150600D01*
X16441D01*
X18441Y-163600D02*
Y-162267D01*
X19107Y-161601D01*
X19774Y-162267D01*
Y-163600D01*
Y-162600D01*
X18441D01*
X16441Y-167600D02*
Y-166267D01*
X17107Y-165601D01*
X17774Y-166267D01*
Y-167600D01*
Y-166600D01*
X16441D01*
X18441Y-171600D02*
Y-170267D01*
X19107Y-169601D01*
X19774Y-170267D01*
Y-171600D01*
Y-170600D01*
X18441D01*
X16441Y-191600D02*
Y-190267D01*
X17107Y-189601D01*
X17774Y-190267D01*
Y-191600D01*
Y-190600D01*
X16441D01*
X18441Y-195600D02*
Y-194267D01*
X19107Y-193601D01*
X19774Y-194267D01*
Y-195600D01*
Y-194600D01*
X18441D01*
X16441Y-199600D02*
Y-198267D01*
X17107Y-197601D01*
X17774Y-198267D01*
Y-199600D01*
Y-198600D01*
X16441D01*
X18441Y-203600D02*
Y-202267D01*
X19107Y-201601D01*
X19774Y-202267D01*
Y-203600D01*
Y-202600D01*
X18441D01*
X16441Y-215600D02*
Y-214267D01*
X17107Y-213601D01*
X17774Y-214267D01*
Y-215600D01*
Y-214600D01*
X16441D01*
X18441Y-219600D02*
Y-218267D01*
X19107Y-217601D01*
X19774Y-218267D01*
Y-219600D01*
Y-218600D01*
X18441D01*
X16441Y-223600D02*
Y-222267D01*
X17107Y-221601D01*
X17774Y-222267D01*
Y-223600D01*
Y-222600D01*
X16441D01*
X18441Y-235600D02*
Y-234267D01*
X19107Y-233601D01*
X19774Y-234267D01*
Y-235600D01*
Y-234600D01*
X18441D01*
Y-243600D02*
Y-242267D01*
X19107Y-241601D01*
X19774Y-242267D01*
Y-243600D01*
Y-242600D01*
X18441D01*
X16441Y-247600D02*
Y-246267D01*
X17107Y-245601D01*
X17774Y-246267D01*
Y-247600D01*
Y-246600D01*
X16441D01*
X18441Y-251600D02*
Y-250267D01*
X19107Y-249601D01*
X19774Y-250267D01*
Y-251600D01*
Y-250600D01*
X18441D01*
X16441Y-255600D02*
Y-254267D01*
X17107Y-253601D01*
X17774Y-254267D01*
Y-255600D01*
Y-254600D01*
X16441D01*
X18441Y-259600D02*
Y-258267D01*
X19107Y-257601D01*
X19774Y-258267D01*
Y-259600D01*
Y-258600D01*
X18441D01*
Y-267600D02*
Y-266267D01*
X19107Y-265601D01*
X19774Y-266267D01*
Y-267600D01*
Y-266600D01*
X18441D01*
X16441Y-271600D02*
Y-270267D01*
X17107Y-269601D01*
X17774Y-270267D01*
Y-271600D01*
Y-270600D01*
X16441D01*
X18441Y-275600D02*
Y-274267D01*
X19107Y-273601D01*
X19774Y-274267D01*
Y-275600D01*
Y-274600D01*
X18441D01*
X16441Y-279600D02*
Y-278267D01*
X17107Y-277601D01*
X17774Y-278267D01*
Y-279600D01*
Y-278600D01*
X16441D01*
X18441Y-291600D02*
Y-290267D01*
X19107Y-289601D01*
X19774Y-290267D01*
Y-291600D01*
Y-290600D01*
X18441D01*
Y-299600D02*
Y-298267D01*
X19107Y-297601D01*
X19774Y-298267D01*
Y-299600D01*
Y-298600D01*
X18441D01*
X16441Y-303600D02*
Y-302267D01*
X17107Y-301601D01*
X17774Y-302267D01*
Y-303600D01*
Y-302600D01*
X16441D01*
X18441Y-307600D02*
Y-306267D01*
X19107Y-305601D01*
X19774Y-306267D01*
Y-307600D01*
Y-306600D01*
X18441D01*
X16441Y-311600D02*
Y-310267D01*
X17107Y-309601D01*
X17774Y-310267D01*
Y-311600D01*
Y-310600D01*
X16441D01*
X18441Y-323600D02*
Y-322267D01*
X19107Y-321601D01*
X19774Y-322267D01*
Y-323600D01*
Y-322600D01*
X18441D01*
X16441Y-327600D02*
Y-326267D01*
X17107Y-325601D01*
X17774Y-326267D01*
Y-327600D01*
Y-326600D01*
X16441D01*
X18441Y-339600D02*
Y-338267D01*
X19107Y-337601D01*
X19774Y-338267D01*
Y-339600D01*
Y-338600D01*
X18441D01*
X16441Y-343600D02*
Y-342267D01*
X17107Y-341601D01*
X17774Y-342267D01*
Y-343600D01*
Y-342600D01*
X16441D01*
Y-351600D02*
Y-350267D01*
X17107Y-349601D01*
X17774Y-350267D01*
Y-351600D01*
Y-350600D01*
X16441D01*
X14441Y-139600D02*
Y-138267D01*
X15107Y-137601D01*
X15774Y-138267D01*
Y-139600D01*
Y-138600D01*
X14441D01*
X12441Y-143600D02*
Y-142267D01*
X13107Y-141601D01*
X13774Y-142267D01*
Y-143600D01*
Y-142600D01*
X12441D01*
X14441Y-147600D02*
Y-146267D01*
X15107Y-145601D01*
X15774Y-146267D01*
Y-147600D01*
Y-146600D01*
X14441D01*
X12441Y-151600D02*
Y-150267D01*
X13107Y-149601D01*
X13774Y-150267D01*
Y-151600D01*
Y-150600D01*
X12441D01*
X14441Y-163600D02*
Y-162267D01*
X15107Y-161601D01*
X15774Y-162267D01*
Y-163600D01*
Y-162600D01*
X14441D01*
X12441Y-167600D02*
Y-166267D01*
X13107Y-165601D01*
X13774Y-166267D01*
Y-167600D01*
Y-166600D01*
X12441D01*
X14441Y-171600D02*
Y-170267D01*
X15107Y-169601D01*
X15774Y-170267D01*
Y-171600D01*
Y-170600D01*
X14441D01*
X12441Y-191600D02*
Y-190267D01*
X13107Y-189601D01*
X13774Y-190267D01*
Y-191600D01*
Y-190600D01*
X12441D01*
X14441Y-195600D02*
Y-194267D01*
X15107Y-193601D01*
X15774Y-194267D01*
Y-195600D01*
Y-194600D01*
X14441D01*
X12441Y-199600D02*
Y-198267D01*
X13107Y-197601D01*
X13774Y-198267D01*
Y-199600D01*
Y-198600D01*
X12441D01*
X14441Y-203600D02*
Y-202267D01*
X15107Y-201601D01*
X15774Y-202267D01*
Y-203600D01*
Y-202600D01*
X14441D01*
X12441Y-215600D02*
Y-214267D01*
X13107Y-213601D01*
X13774Y-214267D01*
Y-215600D01*
Y-214600D01*
X12441D01*
X14441Y-219600D02*
Y-218267D01*
X15107Y-217601D01*
X15774Y-218267D01*
Y-219600D01*
Y-218600D01*
X14441D01*
X12441Y-223600D02*
Y-222267D01*
X13107Y-221601D01*
X13774Y-222267D01*
Y-223600D01*
Y-222600D01*
X12441D01*
X14441Y-243600D02*
Y-242267D01*
X15107Y-241601D01*
X15774Y-242267D01*
Y-243600D01*
Y-242600D01*
X14441D01*
X12441Y-247600D02*
Y-246267D01*
X13107Y-245601D01*
X13774Y-246267D01*
Y-247600D01*
Y-246600D01*
X12441D01*
X14441Y-251600D02*
Y-250267D01*
X15107Y-249601D01*
X15774Y-250267D01*
Y-251600D01*
Y-250600D01*
X14441D01*
X12441Y-255600D02*
Y-254267D01*
X13107Y-253601D01*
X13774Y-254267D01*
Y-255600D01*
Y-254600D01*
X12441D01*
X14441Y-259600D02*
Y-258267D01*
X15107Y-257601D01*
X15774Y-258267D01*
Y-259600D01*
Y-258600D01*
X14441D01*
Y-267600D02*
Y-266267D01*
X15107Y-265601D01*
X15774Y-266267D01*
Y-267600D01*
Y-266600D01*
X14441D01*
X12441Y-271600D02*
Y-270267D01*
X13107Y-269601D01*
X13774Y-270267D01*
Y-271600D01*
Y-270600D01*
X12441D01*
X14441Y-275600D02*
Y-274267D01*
X15107Y-273601D01*
X15774Y-274267D01*
Y-275600D01*
Y-274600D01*
X14441D01*
X12441Y-279600D02*
Y-278267D01*
X13107Y-277601D01*
X13774Y-278267D01*
Y-279600D01*
Y-278600D01*
X12441D01*
X14441Y-291600D02*
Y-290267D01*
X15107Y-289601D01*
X15774Y-290267D01*
Y-291600D01*
Y-290600D01*
X14441D01*
Y-299600D02*
Y-298267D01*
X15107Y-297601D01*
X15774Y-298267D01*
Y-299600D01*
Y-298600D01*
X14441D01*
X12441Y-303600D02*
Y-302267D01*
X13107Y-301601D01*
X13774Y-302267D01*
Y-303600D01*
Y-302600D01*
X12441D01*
X14441Y-307600D02*
Y-306267D01*
X15107Y-305601D01*
X15774Y-306267D01*
Y-307600D01*
Y-306600D01*
X14441D01*
X12441Y-311600D02*
Y-310267D01*
X13107Y-309601D01*
X13774Y-310267D01*
Y-311600D01*
Y-310600D01*
X12441D01*
X14441Y-323600D02*
Y-322267D01*
X15107Y-321601D01*
X15774Y-322267D01*
Y-323600D01*
Y-322600D01*
X14441D01*
X12441Y-327600D02*
Y-326267D01*
X13107Y-325601D01*
X13774Y-326267D01*
Y-327600D01*
Y-326600D01*
X12441D01*
X14441Y-331600D02*
Y-330267D01*
X15107Y-329601D01*
X15774Y-330267D01*
Y-331600D01*
Y-330600D01*
X14441D01*
X12441Y-343600D02*
Y-342267D01*
X13107Y-341601D01*
X13774Y-342267D01*
Y-343600D01*
Y-342600D01*
X12441D01*
Y-351600D02*
Y-350267D01*
X13107Y-349601D01*
X13774Y-350267D01*
Y-351600D01*
Y-350600D01*
X12441D01*
X10441Y-139600D02*
Y-138267D01*
X11107Y-137601D01*
X11774Y-138267D01*
Y-139600D01*
Y-138600D01*
X10441D01*
Y-163600D02*
Y-162267D01*
X11107Y-161601D01*
X11774Y-162267D01*
Y-163600D01*
Y-162600D01*
X10441D01*
Y-171600D02*
Y-170267D01*
X11107Y-169601D01*
X11774Y-170267D01*
Y-171600D01*
Y-170600D01*
X10441D01*
X8441Y-191600D02*
Y-190267D01*
X9107Y-189601D01*
X9774Y-190267D01*
Y-191600D01*
Y-190600D01*
X8441D01*
X10441Y-195600D02*
Y-194267D01*
X11107Y-193601D01*
X11774Y-194267D01*
Y-195600D01*
Y-194600D01*
X10441D01*
Y-203600D02*
Y-202267D01*
X11107Y-201601D01*
X11774Y-202267D01*
Y-203600D01*
Y-202600D01*
X10441D01*
Y-227600D02*
Y-226267D01*
X11107Y-225601D01*
X11774Y-226267D01*
Y-227600D01*
Y-226600D01*
X10441D01*
Y-243600D02*
Y-242267D01*
X11107Y-241601D01*
X11774Y-242267D01*
Y-243600D01*
Y-242600D01*
X10441D01*
X8441Y-247600D02*
Y-246267D01*
X9107Y-245601D01*
X9774Y-246267D01*
Y-247600D01*
Y-246600D01*
X8441D01*
X10441Y-251600D02*
Y-250267D01*
X11107Y-249601D01*
X11774Y-250267D01*
Y-251600D01*
Y-250600D01*
X10441D01*
Y-259600D02*
Y-258267D01*
X11107Y-257601D01*
X11774Y-258267D01*
Y-259600D01*
Y-258600D01*
X10441D01*
Y-267600D02*
Y-266267D01*
X11107Y-265601D01*
X11774Y-266267D01*
Y-267600D01*
Y-266600D01*
X10441D01*
Y-275600D02*
Y-274267D01*
X11107Y-273601D01*
X11774Y-274267D01*
Y-275600D01*
Y-274600D01*
X10441D01*
X8441Y-279600D02*
Y-278267D01*
X9107Y-277601D01*
X9774Y-278267D01*
Y-279600D01*
Y-278600D01*
X8441D01*
X10441Y-299600D02*
Y-298267D01*
X11107Y-297601D01*
X11774Y-298267D01*
Y-299600D01*
Y-298600D01*
X10441D01*
Y-323600D02*
Y-322267D01*
X11107Y-321601D01*
X11774Y-322267D01*
Y-323600D01*
Y-322600D01*
X10441D01*
Y-331600D02*
Y-330267D01*
X11107Y-329601D01*
X11774Y-330267D01*
Y-331600D01*
Y-330600D01*
X10441D01*
X8441Y-351600D02*
Y-350267D01*
X9107Y-349601D01*
X9774Y-350267D01*
Y-351600D01*
Y-350600D01*
X8441D01*
X6441Y-139600D02*
Y-138267D01*
X7107Y-137601D01*
X7774Y-138267D01*
Y-139600D01*
Y-138600D01*
X6441D01*
X4441Y-191600D02*
Y-190267D01*
X5107Y-189601D01*
X5774Y-190267D01*
Y-191600D01*
Y-190600D01*
X4441D01*
X6441Y-243600D02*
Y-242267D01*
X7107Y-241601D01*
X7774Y-242267D01*
Y-243600D01*
Y-242600D01*
X6441D01*
X4441Y-351600D02*
Y-350267D01*
X5107Y-349601D01*
X5774Y-350267D01*
Y-351600D01*
Y-350600D01*
X4441D01*
X2441Y-243600D02*
Y-242267D01*
X3107Y-241601D01*
X3774Y-242267D01*
Y-243600D01*
Y-242600D01*
X2441D01*
X441Y-351600D02*
Y-350267D01*
X1107Y-349601D01*
X1774Y-350267D01*
Y-351600D01*
Y-350600D01*
X441D01*
X-3559Y-191600D02*
Y-190267D01*
X-2893Y-189601D01*
X-2226Y-190267D01*
Y-191600D01*
Y-190600D01*
X-3559D01*
X-1559Y-243600D02*
Y-242267D01*
X-893Y-241601D01*
X-226Y-242267D01*
Y-243600D01*
Y-242600D01*
X-1559D01*
X-3559Y-351600D02*
Y-350267D01*
X-2893Y-349601D01*
X-2226Y-350267D01*
Y-351600D01*
Y-350600D01*
X-3559D01*
X-5559Y-139600D02*
Y-138267D01*
X-4893Y-137601D01*
X-4226Y-138267D01*
Y-139600D01*
Y-138600D01*
X-5559D01*
X-7559Y-143600D02*
Y-142267D01*
X-6893Y-141601D01*
X-6226Y-142267D01*
Y-143600D01*
Y-142600D01*
X-7559D01*
Y-167600D02*
Y-166267D01*
X-6893Y-165601D01*
X-6226Y-166267D01*
Y-167600D01*
Y-166600D01*
X-7559D01*
Y-191600D02*
Y-190267D01*
X-6893Y-189601D01*
X-6226Y-190267D01*
Y-191600D01*
Y-190600D01*
X-7559D01*
Y-199600D02*
Y-198267D01*
X-6893Y-197601D01*
X-6226Y-198267D01*
Y-199600D01*
Y-198600D01*
X-7559D01*
Y-223600D02*
Y-222267D01*
X-6893Y-221601D01*
X-6226Y-222267D01*
Y-223600D01*
Y-222600D01*
X-7559D01*
X-5559Y-227600D02*
Y-226267D01*
X-4893Y-225601D01*
X-4226Y-226267D01*
Y-227600D01*
Y-226600D01*
X-5559D01*
Y-243600D02*
Y-242267D01*
X-4893Y-241601D01*
X-4226Y-242267D01*
Y-243600D01*
Y-242600D01*
X-5559D01*
X-7559Y-247600D02*
Y-246267D01*
X-6893Y-245601D01*
X-6226Y-246267D01*
Y-247600D01*
Y-246600D01*
X-7559D01*
Y-279600D02*
Y-278267D01*
X-6893Y-277601D01*
X-6226Y-278267D01*
Y-279600D01*
Y-278600D01*
X-7559D01*
X-5559Y-299600D02*
Y-298267D01*
X-4893Y-297601D01*
X-4226Y-298267D01*
Y-299600D01*
Y-298600D01*
X-5559D01*
X-7559Y-303600D02*
Y-302267D01*
X-6893Y-301601D01*
X-6226Y-302267D01*
Y-303600D01*
Y-302600D01*
X-7559D01*
Y-327600D02*
Y-326267D01*
X-6893Y-325601D01*
X-6226Y-326267D01*
Y-327600D01*
Y-326600D01*
X-7559D01*
Y-351600D02*
Y-350267D01*
X-6893Y-349601D01*
X-6226Y-350267D01*
Y-351600D01*
Y-350600D01*
X-7559D01*
X-9559Y-139600D02*
Y-138267D01*
X-8893Y-137601D01*
X-8226Y-138267D01*
Y-139600D01*
Y-138600D01*
X-9559D01*
Y-171600D02*
Y-170267D01*
X-8893Y-169601D01*
X-8226Y-170267D01*
Y-171600D01*
Y-170600D01*
X-9559D01*
X-11559Y-191600D02*
Y-190267D01*
X-10893Y-189601D01*
X-10226Y-190267D01*
Y-191600D01*
Y-190600D01*
X-11559D01*
X-9559Y-195600D02*
Y-194267D01*
X-8893Y-193601D01*
X-8226Y-194267D01*
Y-195600D01*
Y-194600D01*
X-9559D01*
Y-227600D02*
Y-226267D01*
X-8893Y-225601D01*
X-8226Y-226267D01*
Y-227600D01*
Y-226600D01*
X-9559D01*
Y-243600D02*
Y-242267D01*
X-8893Y-241601D01*
X-8226Y-242267D01*
Y-243600D01*
Y-242600D01*
X-9559D01*
X-11559Y-247600D02*
Y-246267D01*
X-10893Y-245601D01*
X-10226Y-246267D01*
Y-247600D01*
Y-246600D01*
X-11559D01*
X-9559Y-251600D02*
Y-250267D01*
X-8893Y-249601D01*
X-8226Y-250267D01*
Y-251600D01*
Y-250600D01*
X-9559D01*
Y-275600D02*
Y-274267D01*
X-8893Y-273601D01*
X-8226Y-274267D01*
Y-275600D01*
Y-274600D01*
X-9559D01*
X-11559Y-279600D02*
Y-278267D01*
X-10893Y-277601D01*
X-10226Y-278267D01*
Y-279600D01*
Y-278600D01*
X-11559D01*
X-9559Y-299600D02*
Y-298267D01*
X-8893Y-297601D01*
X-8226Y-298267D01*
Y-299600D01*
Y-298600D01*
X-9559D01*
Y-331600D02*
Y-330267D01*
X-8893Y-329601D01*
X-8226Y-330267D01*
Y-331600D01*
Y-330600D01*
X-9559D01*
X-11559Y-351600D02*
Y-350267D01*
X-10893Y-349601D01*
X-10226Y-350267D01*
Y-351600D01*
Y-350600D01*
X-11559D01*
X-13559Y-139600D02*
Y-138267D01*
X-12893Y-137601D01*
X-12226Y-138267D01*
Y-139600D01*
Y-138600D01*
X-13559D01*
X-15559Y-191600D02*
Y-190267D01*
X-14893Y-189601D01*
X-14226Y-190267D01*
Y-191600D01*
Y-190600D01*
X-15559D01*
X-13559Y-243600D02*
Y-242267D01*
X-12893Y-241601D01*
X-12226Y-242267D01*
Y-243600D01*
Y-242600D01*
X-13559D01*
X-15559Y-351600D02*
Y-350267D01*
X-14893Y-349601D01*
X-14226Y-350267D01*
Y-351600D01*
Y-350600D01*
X-15559D01*
X-19559Y-263600D02*
Y-262267D01*
X-18893Y-261601D01*
X-18226Y-262267D01*
Y-263600D01*
Y-262600D01*
X-19559D01*
Y-351600D02*
Y-350267D01*
X-18893Y-349601D01*
X-18226Y-350267D01*
Y-351600D01*
Y-350600D01*
X-19559D01*
X-23559Y-159600D02*
Y-158267D01*
X-22893Y-157601D01*
X-22226Y-158267D01*
Y-159600D01*
Y-158600D01*
X-23559D01*
Y-191600D02*
Y-190267D01*
X-22893Y-189601D01*
X-22226Y-190267D01*
Y-191600D01*
Y-190600D01*
X-23559D01*
X-21559Y-211600D02*
Y-210267D01*
X-20893Y-209601D01*
X-20226Y-210267D01*
Y-211600D01*
Y-210600D01*
X-21559D01*
X-23559Y-263600D02*
Y-262267D01*
X-22893Y-261601D01*
X-22226Y-262267D01*
Y-263600D01*
Y-262600D01*
X-23559D01*
X-21559Y-315600D02*
Y-314267D01*
X-20893Y-313601D01*
X-20226Y-314267D01*
Y-315600D01*
Y-314600D01*
X-21559D01*
X-23559Y-351600D02*
Y-350267D01*
X-22893Y-349601D01*
X-22226Y-350267D01*
Y-351600D01*
Y-350600D01*
X-23559D01*
X-25559Y-139600D02*
Y-138267D01*
X-24893Y-137601D01*
X-24226Y-138267D01*
Y-139600D01*
Y-138600D01*
X-25559D01*
Y-155600D02*
Y-154267D01*
X-24893Y-153601D01*
X-24226Y-154267D01*
Y-155600D01*
Y-154600D01*
X-25559D01*
Y-211600D02*
Y-210267D01*
X-24893Y-209601D01*
X-24226Y-210267D01*
Y-211600D01*
Y-210600D01*
X-25559D01*
Y-259600D02*
Y-258267D01*
X-24893Y-257601D01*
X-24226Y-258267D01*
Y-259600D01*
Y-258600D01*
X-25559D01*
Y-267600D02*
Y-266267D01*
X-24893Y-265601D01*
X-24226Y-266267D01*
Y-267600D01*
Y-266600D01*
X-25559D01*
Y-299600D02*
Y-298267D01*
X-24893Y-297601D01*
X-24226Y-298267D01*
Y-299600D01*
Y-298600D01*
X-25559D01*
Y-315600D02*
Y-314267D01*
X-24893Y-313601D01*
X-24226Y-314267D01*
Y-315600D01*
Y-314600D01*
X-25559D01*
X234252Y-133742D02*
Y-132409D01*
X234918Y-131742D01*
X235585Y-132409D01*
Y-133742D01*
Y-132742D01*
X234252D01*
X263779Y-106151D02*
Y-104818D01*
X264446Y-104152D01*
X265112Y-104818D01*
Y-106151D01*
Y-105151D01*
X263779D01*
X71850Y-147638D02*
Y-146305D01*
X72517Y-145638D01*
X73183Y-146305D01*
Y-147638D01*
Y-146638D01*
X71850D01*
X75787Y-131890D02*
Y-130557D01*
X76454Y-129890D01*
X77120Y-130557D01*
Y-131890D01*
Y-130890D01*
X75787D01*
X623000Y-37402D02*
Y-36069D01*
X623666Y-35402D01*
X624333Y-36069D01*
Y-37402D01*
Y-36402D01*
X623000D01*
X610236Y-8858D02*
Y-7525D01*
X610903Y-6859D01*
X611569Y-7525D01*
Y-8858D01*
Y-7859D01*
X610236D01*
X609252Y-26575D02*
Y-25242D01*
X609918Y-24576D01*
X610585Y-25242D01*
Y-26575D01*
Y-25575D01*
X609252D01*
X98425Y-102362D02*
Y-101029D01*
X99092Y-100363D01*
X99758Y-101029D01*
Y-102362D01*
Y-101363D01*
X98425D01*
X89567Y-102362D02*
Y-101029D01*
X90233Y-100363D01*
X90900Y-101029D01*
Y-102362D01*
Y-101363D01*
X89567D01*
X85630Y-313976D02*
Y-312644D01*
X86296Y-311977D01*
X86963Y-312644D01*
Y-313976D01*
Y-312977D01*
X85630D01*
X86614Y-258858D02*
Y-257525D01*
X87281Y-256859D01*
X87947Y-257525D01*
Y-258858D01*
Y-257859D01*
X86614D01*
X81693Y-205709D02*
Y-204376D01*
X82359Y-203709D01*
X83026Y-204376D01*
Y-205709D01*
Y-204709D01*
X81693D01*
X360236Y-268586D02*
Y-267253D01*
X360903Y-266586D01*
X361569Y-267253D01*
Y-268586D01*
Y-267586D01*
X360236D01*
Y-272490D02*
Y-271157D01*
X360903Y-270490D01*
X361569Y-271157D01*
Y-272490D01*
Y-271490D01*
X360236D01*
X63976Y-227362D02*
Y-226029D01*
X64643Y-225363D01*
X65309Y-226029D01*
Y-227362D01*
Y-226362D01*
X63976D01*
X68898Y-285433D02*
Y-284100D01*
X69564Y-283434D01*
X70231Y-284100D01*
Y-285433D01*
Y-284433D01*
X68898D01*
X67913Y-340551D02*
Y-339218D01*
X68580Y-338552D01*
X69246Y-339218D01*
Y-340551D01*
Y-339551D01*
X67913D01*
X68573Y-179321D02*
Y-177988D01*
X69240Y-177321D01*
X69906Y-177988D01*
Y-179321D01*
Y-178321D01*
X68573D01*
X44291Y-252953D02*
Y-251620D01*
X44958Y-250953D01*
X45624Y-251620D01*
Y-252953D01*
Y-251953D01*
X44291D01*
Y-272638D02*
Y-271305D01*
X44958Y-270638D01*
X45624Y-271305D01*
Y-272638D01*
Y-271638D01*
X44291D01*
Y-326772D02*
Y-325439D01*
X44958Y-324772D01*
X45624Y-325439D01*
Y-326772D01*
Y-325772D01*
X44291D01*
Y-307087D02*
Y-305754D01*
X44958Y-305087D01*
X45624Y-305754D01*
Y-307087D01*
Y-306087D01*
X44291D01*
X26575Y-291339D02*
Y-290006D01*
X27241Y-289339D01*
X27908Y-290006D01*
Y-291339D01*
Y-290339D01*
X26575D01*
X31496Y-189961D02*
Y-188628D01*
X32162Y-187961D01*
X32829Y-188628D01*
Y-189961D01*
Y-188961D01*
X31496D01*
X44291Y-147638D02*
Y-146305D01*
X44958Y-145638D01*
X45624Y-146305D01*
Y-147638D01*
Y-146638D01*
X44291D01*
Y-167323D02*
Y-165990D01*
X44958Y-165323D01*
X45624Y-165990D01*
Y-167323D01*
Y-166323D01*
X44291D01*
Y-200787D02*
Y-199454D01*
X44958Y-198788D01*
X45624Y-199454D01*
Y-200787D01*
Y-199788D01*
X44291D01*
Y-220472D02*
Y-219140D01*
X44958Y-218473D01*
X45624Y-219140D01*
Y-220472D01*
Y-219473D01*
X44291D01*
X325787Y-243205D02*
Y-241872D01*
X326454Y-241205D01*
X327120Y-241872D01*
Y-243205D01*
Y-242205D01*
X325787D01*
Y-233362D02*
Y-232029D01*
X326454Y-231363D01*
X327120Y-232029D01*
Y-233362D01*
Y-232363D01*
X325787D01*
X103409Y-141732D02*
Y-140399D01*
X104076Y-139733D01*
X104742Y-140399D01*
Y-141732D01*
Y-140733D01*
X103409D01*
X103347Y-110236D02*
Y-108903D01*
X104013Y-108237D01*
X104679Y-108903D01*
Y-110236D01*
Y-109237D01*
X103347D01*
X119095Y-126047D02*
Y-124714D01*
X119761Y-124047D01*
X120427Y-124714D01*
Y-126047D01*
Y-125047D01*
X119095D01*
X518701Y-104214D02*
Y-102881D01*
X519367Y-102215D01*
X520034Y-102881D01*
Y-104214D01*
Y-103215D01*
X518701D01*
X519587Y-134596D02*
Y-133263D01*
X520253Y-132597D01*
X520920Y-133263D01*
Y-134596D01*
Y-133596D01*
X519587D01*
X528543Y-104214D02*
Y-102881D01*
X529210Y-102215D01*
X529876Y-102881D01*
Y-104214D01*
Y-103215D01*
X528543D01*
X658465Y-21899D02*
Y-20566D01*
X659131Y-19900D01*
X659797Y-20566D01*
Y-21899D01*
Y-20899D01*
X658465D01*
X625000Y-29773D02*
Y-28440D01*
X625667Y-27774D01*
X626333Y-28440D01*
Y-29773D01*
Y-28774D01*
X625000D01*
X114173Y-83088D02*
Y-81755D01*
X114840Y-81089D01*
X115506Y-81755D01*
Y-83088D01*
Y-82089D01*
X114173D01*
X441929Y-122883D02*
Y-121551D01*
X442596Y-120884D01*
X443262Y-121551D01*
Y-122883D01*
Y-121884D01*
X441929D01*
X129921Y-79576D02*
Y-78243D01*
X130588Y-77577D01*
X131254Y-78243D01*
Y-79576D01*
Y-78577D01*
X129921D01*
X163071Y-390730D02*
Y-389397D01*
X163737Y-388731D01*
X164404Y-389397D01*
Y-390730D01*
Y-389730D01*
X163071D01*
X99410Y-50049D02*
Y-48716D01*
X100076Y-48050D01*
X100742Y-48716D01*
Y-50049D01*
Y-49049D01*
X99410D01*
X26495Y-8991D02*
Y-7659D01*
X27162Y-6992D01*
X27828Y-7659D01*
Y-8991D01*
Y-7992D01*
X26495D01*
X512657Y-270462D02*
Y-269129D01*
X513324Y-268463D01*
X513990Y-269129D01*
Y-270462D01*
Y-269463D01*
X512657D01*
X259285Y-390247D02*
Y-388914D01*
X259952Y-388247D01*
X260618Y-388914D01*
Y-390247D01*
Y-389247D01*
X259285D01*
X267204Y-390009D02*
Y-388677D01*
X267871Y-388010D01*
X268537Y-388677D01*
Y-390009D01*
Y-389010D01*
X267204D01*
X216162Y-390947D02*
Y-389614D01*
X216829Y-388948D01*
X217495Y-389614D01*
Y-390947D01*
Y-389948D01*
X216162D01*
X235144Y-390416D02*
Y-389083D01*
X235811Y-388416D01*
X236477Y-389083D01*
Y-390416D01*
Y-389416D01*
X235144D01*
X251456Y-390009D02*
Y-388677D01*
X252123Y-388010D01*
X252789Y-388677D01*
Y-390009D01*
Y-389010D01*
X251456D01*
X226063Y-390722D02*
Y-389389D01*
X226729Y-388723D01*
X227396Y-389389D01*
Y-390722D01*
Y-389722D01*
X226063D01*
X281201Y-390009D02*
Y-388677D01*
X281867Y-388010D01*
X282534Y-388677D01*
Y-390009D01*
Y-389010D01*
X281201D01*
X174941Y-390600D02*
Y-389267D01*
X175607Y-388601D01*
X176274Y-389267D01*
Y-390600D01*
Y-389600D01*
X174941D01*
X202441Y-390600D02*
Y-389267D01*
X203107Y-388601D01*
X203774Y-389267D01*
Y-390600D01*
Y-389600D01*
X202441D01*
X544291Y-199655D02*
Y-198322D01*
X544958Y-197656D01*
X545624Y-198322D01*
Y-199655D01*
Y-198655D01*
X544291D01*
X509842Y-197687D02*
Y-196354D01*
X510509Y-195687D01*
X511175Y-196354D01*
Y-197687D01*
Y-196687D01*
X509842D01*
X544291Y-201624D02*
Y-200291D01*
X544958Y-199624D01*
X545624Y-200291D01*
Y-201624D01*
Y-200624D01*
X544291D01*
X509842Y-199655D02*
Y-198322D01*
X510509Y-197656D01*
X511175Y-198322D01*
Y-199655D01*
Y-198655D01*
X509842D01*
Y-201624D02*
Y-200291D01*
X510509Y-199624D01*
X511175Y-200291D01*
Y-201624D01*
Y-200624D01*
X509842D01*
X544291Y-197687D02*
Y-196354D01*
X544958Y-195687D01*
X545624Y-196354D01*
Y-197687D01*
Y-196687D01*
X544291D01*
X509842Y-195718D02*
Y-194385D01*
X510509Y-193719D01*
X511175Y-194385D01*
Y-195718D01*
Y-194718D01*
X509842D01*
X361811Y-207087D02*
Y-205754D01*
X362477Y-205087D01*
X363144Y-205754D01*
Y-207087D01*
Y-206087D01*
X361811D01*
X361417Y-203150D02*
Y-201817D01*
X362084Y-201150D01*
X362750Y-201817D01*
Y-203150D01*
Y-202150D01*
X361417D01*
X326969Y-197573D02*
Y-196240D01*
X327635Y-195574D01*
X328301Y-196240D01*
Y-197573D01*
Y-196574D01*
X326969D01*
X326966Y-195171D02*
Y-193838D01*
X327633Y-193172D01*
X328299Y-193838D01*
Y-195171D01*
Y-194172D01*
X326966D01*
X366535Y-202362D02*
Y-201029D01*
X367202Y-200363D01*
X367868Y-201029D01*
Y-202362D01*
Y-201362D01*
X366535D01*
X358661Y-194488D02*
Y-193155D01*
X359328Y-192489D01*
X359994Y-193155D01*
Y-194488D01*
Y-193489D01*
X358661D01*
X634252Y-314567D02*
Y-313234D01*
X634918Y-312568D01*
X635585Y-313234D01*
Y-314567D01*
Y-313567D01*
X634252D01*
X653150Y-314567D02*
Y-313234D01*
X653816Y-312568D01*
X654483Y-313234D01*
Y-314567D01*
Y-313567D01*
X653150D01*
X509391Y-350636D02*
Y-349303D01*
X510057Y-348636D01*
X510724Y-349303D01*
Y-350636D01*
Y-349636D01*
X509391D01*
X508997Y-335675D02*
Y-334342D01*
X509663Y-333676D01*
X510330Y-334342D01*
Y-335675D01*
Y-334675D01*
X508997D01*
X447244Y-324852D02*
Y-323519D01*
X447910Y-322853D01*
X448577Y-323519D01*
Y-324852D01*
Y-323852D01*
X447244D01*
X451181Y-324852D02*
Y-323519D01*
X451848Y-322853D01*
X452514Y-323519D01*
Y-324852D01*
Y-323852D01*
X451181D01*
X433858Y-324852D02*
Y-323519D01*
X434525Y-322853D01*
X435191Y-323519D01*
Y-324852D01*
Y-323852D01*
X433858D01*
X460630Y-324852D02*
Y-323519D01*
X461296Y-322853D01*
X461963Y-323519D01*
Y-324852D01*
Y-323852D01*
X460630D01*
X437795Y-324852D02*
Y-323519D01*
X438462Y-322853D01*
X439128Y-323519D01*
Y-324852D01*
Y-323852D01*
X437795D01*
X431102Y-324852D02*
Y-323519D01*
X431769Y-322853D01*
X432435Y-323519D01*
Y-324852D01*
Y-323852D01*
X431102D01*
X444488Y-324852D02*
Y-323519D01*
X445155Y-322853D01*
X445821Y-323519D01*
Y-324852D01*
Y-323852D01*
X444488D01*
X457480Y-324852D02*
Y-323519D01*
X458147Y-322853D01*
X458813Y-323519D01*
Y-324852D01*
Y-323852D01*
X457480D01*
X453937Y-324852D02*
Y-323519D01*
X454603Y-322853D01*
X455270Y-323519D01*
Y-324852D01*
Y-323852D01*
X453937D01*
X440551Y-324852D02*
Y-323519D01*
X441218Y-322853D01*
X441884Y-323519D01*
Y-324852D01*
Y-323852D01*
X440551D01*
X222638Y-374655D02*
Y-373322D01*
X223304Y-372656D01*
X223971Y-373322D01*
Y-374655D01*
Y-373655D01*
X222638D01*
X218445Y-374108D02*
Y-372775D01*
X219111Y-372108D01*
X219778Y-372775D01*
Y-374108D01*
Y-373108D01*
X218445D01*
X453937Y-306742D02*
Y-305409D01*
X454603Y-304742D01*
X455270Y-305409D01*
Y-306742D01*
Y-305742D01*
X453937D01*
X451181Y-306742D02*
Y-305409D01*
X451848Y-304742D01*
X452514Y-305409D01*
Y-306742D01*
Y-305742D01*
X451181D01*
X109409Y-140111D02*
Y-138778D01*
X110076Y-138112D01*
X110742Y-138778D01*
Y-140111D01*
Y-139111D01*
X109409D01*
X105409Y-140111D02*
Y-138778D01*
X106076Y-138112D01*
X106742Y-138778D01*
Y-140111D01*
Y-139111D01*
X105409D01*
X101409Y-140111D02*
Y-138778D01*
X102076Y-138112D01*
X102742Y-138778D01*
Y-140111D01*
Y-139111D01*
X101409D01*
X97409Y-140111D02*
Y-138778D01*
X98076Y-138112D01*
X98742Y-138778D01*
Y-140111D01*
Y-139111D01*
X97409D01*
X65945Y-57923D02*
Y-56590D01*
X66611Y-55923D01*
X67278Y-56590D01*
Y-57923D01*
Y-56923D01*
X65945D01*
X615158Y-8858D02*
Y-7525D01*
X615824Y-6859D01*
X616490Y-7525D01*
Y-8858D01*
Y-7859D01*
X615158D01*
X70866Y-122047D02*
Y-120714D01*
X71533Y-120048D01*
X72199Y-120714D01*
Y-122047D01*
Y-121048D01*
X70866D01*
X360204Y-252984D02*
Y-251651D01*
X360871Y-250985D01*
X361537Y-251651D01*
Y-252984D01*
Y-251985D01*
X360204D01*
X417596Y-175197D02*
Y-173864D01*
X418263Y-173197D01*
X418929Y-173864D01*
Y-175197D01*
Y-174197D01*
X417596D01*
X377921Y-203740D02*
Y-202407D01*
X378588Y-201741D01*
X379254Y-202407D01*
Y-203740D01*
Y-202741D01*
X377921D01*
X372016Y-200787D02*
Y-199454D01*
X372682Y-198788D01*
X373349Y-199454D01*
Y-200787D01*
Y-199788D01*
X372016D01*
X354541Y-223636D02*
Y-222303D01*
X355208Y-221636D01*
X355874Y-222303D01*
Y-223636D01*
Y-222636D01*
X354541D01*
X354452Y-235236D02*
Y-233903D01*
X355118Y-233237D01*
X355785Y-233903D01*
Y-235236D01*
Y-234237D01*
X354452D01*
X356578Y-225247D02*
Y-223914D01*
X357244Y-223248D01*
X357910Y-223914D01*
Y-225247D01*
Y-224247D01*
X356578D01*
X379921Y-201740D02*
Y-200407D01*
X380588Y-199741D01*
X381254Y-200407D01*
Y-201740D01*
Y-200741D01*
X379921D01*
X102528Y-211583D02*
Y-210250D01*
X103194Y-209583D01*
X103860Y-210250D01*
Y-211583D01*
Y-210583D01*
X102528D01*
X97125Y-219488D02*
Y-218155D01*
X97792Y-217489D01*
X98458Y-218155D01*
Y-219488D01*
Y-218489D01*
X97125D01*
X99410Y-216535D02*
Y-215202D01*
X100076Y-214536D01*
X100742Y-215202D01*
Y-216535D01*
Y-215536D01*
X99410D01*
X101378Y-214567D02*
Y-213234D01*
X102044Y-212568D01*
X102711Y-213234D01*
Y-214567D01*
Y-213567D01*
X101378D01*
X86614Y-175197D02*
Y-173864D01*
X87281Y-173197D01*
X87947Y-173864D01*
Y-175197D01*
Y-174197D01*
X86614D01*
X361652Y-235205D02*
Y-233872D01*
X362318Y-233205D01*
X362985Y-233872D01*
Y-235205D01*
Y-234205D01*
X361652D01*
X359131Y-223425D02*
Y-222092D01*
X359797Y-221426D01*
X360464Y-222092D01*
Y-223425D01*
Y-222426D01*
X359131D01*
X361531Y-223425D02*
Y-222092D01*
X362197Y-221426D01*
X362864Y-222092D01*
Y-223425D01*
Y-222426D01*
X361531D01*
X360236Y-262186D02*
Y-260853D01*
X360903Y-260186D01*
X361569Y-260853D01*
Y-262186D01*
Y-261186D01*
X360236D01*
Y-266186D02*
Y-264853D01*
X360903Y-264186D01*
X361569Y-264853D01*
Y-266186D01*
Y-265186D01*
X360236D01*
X85416Y-317699D02*
Y-316366D01*
X86082Y-315700D01*
X86749Y-316366D01*
Y-317699D01*
Y-316700D01*
X85416D01*
X85630Y-263779D02*
Y-262447D01*
X86296Y-261780D01*
X86963Y-262447D01*
Y-263779D01*
Y-262780D01*
X85630D01*
X86562Y-211183D02*
Y-209850D01*
X87229Y-209183D01*
X87895Y-209850D01*
Y-211183D01*
Y-210183D01*
X86562D01*
X411043Y-174974D02*
Y-173641D01*
X411709Y-172975D01*
X412376Y-173641D01*
Y-174974D01*
Y-173974D01*
X411043D01*
X413440Y-174850D02*
Y-173517D01*
X414106Y-172851D01*
X414772Y-173517D01*
Y-174850D01*
Y-173850D01*
X413440D01*
X421596Y-175034D02*
Y-173701D01*
X422263Y-173034D01*
X422929Y-173701D01*
Y-175034D01*
Y-174034D01*
X421596D01*
X406528Y-157767D02*
Y-156434D01*
X407194Y-155767D01*
X407861Y-156434D01*
Y-157767D01*
Y-156767D01*
X406528D01*
X404528Y-163386D02*
Y-162053D01*
X405194Y-161387D01*
X405861Y-162053D01*
Y-163386D01*
Y-162386D01*
X404528D01*
X407480Y-160433D02*
Y-159100D01*
X408147Y-158434D01*
X408813Y-159100D01*
Y-160433D01*
Y-159433D01*
X407480D01*
X86614Y-221457D02*
Y-220124D01*
X87281Y-219457D01*
X87947Y-220124D01*
Y-221457D01*
Y-220457D01*
X86614D01*
X427165Y-175246D02*
Y-173913D01*
X427832Y-173246D01*
X428498Y-173913D01*
Y-175246D01*
Y-174246D01*
X427165D01*
X75787Y-232283D02*
Y-230951D01*
X76454Y-230284D01*
X77120Y-230951D01*
Y-232283D01*
Y-231284D01*
X75787D01*
X87167Y-166377D02*
Y-165044D01*
X87834Y-164378D01*
X88500Y-165044D01*
Y-166377D01*
Y-165377D01*
X87167D01*
X89567Y-166370D02*
Y-165037D01*
X90234Y-164371D01*
X90900Y-165037D01*
Y-166370D01*
Y-165370D01*
X89567D01*
X85630Y-213583D02*
Y-212250D01*
X86296Y-211583D01*
X86963Y-212250D01*
Y-213583D01*
Y-212583D01*
X85630D01*
Y-266179D02*
Y-264847D01*
X86296Y-264180D01*
X86963Y-264847D01*
Y-266179D01*
Y-265180D01*
X85630D01*
Y-320313D02*
Y-318981D01*
X86296Y-318314D01*
X86963Y-318981D01*
Y-320313D01*
Y-319314D01*
X85630D01*
X543276Y-226591D02*
Y-225258D01*
X543942Y-224592D01*
X544608Y-225258D01*
Y-226591D01*
Y-225591D01*
X543276D01*
X544294Y-224248D02*
Y-222915D01*
X544961Y-222248D01*
X545627Y-222915D01*
Y-224248D01*
Y-223248D01*
X544294D01*
X544291Y-233268D02*
Y-231935D01*
X544958Y-231268D01*
X545624Y-231935D01*
Y-233268D01*
Y-232268D01*
X544291D01*
X359252Y-235236D02*
Y-233903D01*
X359918Y-233237D01*
X360585Y-233903D01*
Y-235236D01*
Y-234237D01*
X359252D01*
X356852Y-235236D02*
Y-233903D01*
X357518Y-233237D01*
X358185Y-233903D01*
Y-235236D01*
Y-234237D01*
X356852D01*
X407480Y-163386D02*
Y-162053D01*
X408147Y-161387D01*
X408813Y-162053D01*
Y-163386D01*
Y-162386D01*
X407480D01*
X47244Y-8858D02*
Y-7525D01*
X47910Y-6859D01*
X48577Y-7525D01*
Y-8858D01*
Y-7859D01*
X47244D01*
X40354Y-8858D02*
Y-7525D01*
X41021Y-6859D01*
X41687Y-7525D01*
Y-8858D01*
Y-7859D01*
X40354D01*
X33465Y-8858D02*
Y-7525D01*
X34131Y-6859D01*
X34797Y-7525D01*
Y-8858D01*
Y-7859D01*
X33465D01*
X26575Y19685D02*
Y21018D01*
X27241Y21684D01*
X27908Y21018D01*
Y19685D01*
Y20685D01*
X26575D01*
X86614Y-227362D02*
Y-226029D01*
X87281Y-225363D01*
X87947Y-226029D01*
Y-227362D01*
Y-226362D01*
X86614D01*
X63976Y-221457D02*
Y-220124D01*
X64643Y-219457D01*
X65309Y-220124D01*
Y-221457D01*
Y-220457D01*
X63976D01*
X82677Y-232283D02*
Y-230951D01*
X83344Y-230284D01*
X84010Y-230951D01*
Y-232283D01*
Y-231284D01*
X82677D01*
X63976Y-275590D02*
Y-274258D01*
X64643Y-273591D01*
X65309Y-274258D01*
Y-275590D01*
Y-274591D01*
X63976D01*
X75787Y-285433D02*
Y-284100D01*
X76454Y-283434D01*
X77120Y-284100D01*
Y-285433D01*
Y-284433D01*
X75787D01*
X87598Y-275590D02*
Y-274258D01*
X88265Y-273591D01*
X88931Y-274258D01*
Y-275590D01*
Y-274591D01*
X87598D01*
Y-281496D02*
Y-280163D01*
X88265Y-279497D01*
X88931Y-280163D01*
Y-281496D01*
Y-280496D01*
X87598D01*
X81880Y-287582D02*
Y-286249D01*
X82546Y-285583D01*
X83213Y-286249D01*
Y-287582D01*
Y-286583D01*
X81880D01*
X62992Y-329724D02*
Y-328392D01*
X63659Y-327725D01*
X64325Y-328392D01*
Y-329724D01*
Y-328725D01*
X62992D01*
X74803Y-339567D02*
Y-338234D01*
X75470Y-337568D01*
X76136Y-338234D01*
Y-339567D01*
Y-338567D01*
X74803D01*
X78740Y-340551D02*
Y-339218D01*
X79407Y-338552D01*
X80073Y-339218D01*
Y-340551D01*
Y-339551D01*
X78740D01*
X87598Y-335630D02*
Y-334297D01*
X88265Y-333631D01*
X88931Y-334297D01*
Y-335630D01*
Y-334630D01*
X87598D01*
Y-329724D02*
Y-328392D01*
X88265Y-327725D01*
X88931Y-328392D01*
Y-329724D01*
Y-328725D01*
X87598D01*
X63976Y-179134D02*
Y-177801D01*
X64643Y-177135D01*
X65309Y-177801D01*
Y-179134D01*
Y-178134D01*
X63976D01*
X74803Y-179134D02*
Y-177801D01*
X75470Y-177135D01*
X76136Y-177801D01*
Y-179134D01*
Y-178134D01*
X74803D01*
X86562Y-169257D02*
Y-167924D01*
X87229Y-167258D01*
X87895Y-167924D01*
Y-169257D01*
Y-168257D01*
X86562D01*
X80709Y-180118D02*
Y-178785D01*
X81375Y-178119D01*
X82042Y-178785D01*
Y-180118D01*
Y-179118D01*
X80709D01*
X26575Y-283465D02*
Y-282132D01*
X27241Y-281465D01*
X27908Y-282132D01*
Y-283465D01*
Y-282465D01*
X26575D01*
X30512Y-170276D02*
Y-168943D01*
X31178Y-168276D01*
X31845Y-168943D01*
Y-170276D01*
Y-169276D01*
X30512D01*
X323850Y-241173D02*
Y-239840D01*
X324517Y-239174D01*
X325183Y-239840D01*
Y-241173D01*
Y-240174D01*
X323850D01*
Y-237205D02*
Y-235872D01*
X324517Y-235205D01*
X325183Y-235872D01*
Y-237205D01*
Y-236205D01*
X323850D01*
X323819Y-231299D02*
Y-229966D01*
X324485Y-229300D01*
X325152Y-229966D01*
Y-231299D01*
Y-230299D01*
X323819D01*
X325787Y-229362D02*
Y-228029D01*
X326454Y-227363D01*
X327120Y-228029D01*
Y-229362D01*
Y-228362D01*
X325787D01*
X323819Y-227362D02*
Y-226029D01*
X324485Y-225363D01*
X325152Y-226029D01*
Y-227362D01*
Y-226362D01*
X323819D01*
X325787Y-239205D02*
Y-237872D01*
X326454Y-237205D01*
X327120Y-237872D01*
Y-239205D01*
Y-238205D01*
X325787D01*
X-23622Y-342520D02*
Y-341187D01*
X-22956Y-340520D01*
X-22289Y-341187D01*
Y-342520D01*
Y-341520D01*
X-23622D01*
X89567Y-140270D02*
Y-138937D01*
X90233Y-138271D01*
X90900Y-138937D01*
Y-140270D01*
Y-139270D01*
X89567D01*
X87254Y-139629D02*
Y-138296D01*
X87921Y-137629D01*
X88587Y-138296D01*
Y-139629D01*
Y-138629D01*
X87254D01*
X119095Y-130047D02*
Y-128714D01*
X119761Y-128047D01*
X120427Y-128714D01*
Y-130047D01*
Y-129047D01*
X119095D01*
X117126Y-132047D02*
Y-130714D01*
X117792Y-130048D01*
X118459Y-130714D01*
Y-132047D01*
Y-131048D01*
X117126D01*
X107346Y-110236D02*
Y-108903D01*
X108013Y-108237D01*
X108679Y-108903D01*
Y-110236D01*
Y-109237D01*
X107346D01*
X105347Y-112205D02*
Y-110872D01*
X106013Y-110205D01*
X106679Y-110872D01*
Y-112205D01*
Y-111205D01*
X105347D01*
X99347Y-110236D02*
Y-108903D01*
X100013Y-108237D01*
X100679Y-108903D01*
Y-110236D01*
Y-109237D01*
X99347D01*
X109409Y-112236D02*
Y-110903D01*
X110076Y-110237D01*
X110742Y-110903D01*
Y-112236D01*
Y-111237D01*
X109409D01*
X119095Y-122047D02*
Y-120714D01*
X119761Y-120047D01*
X120427Y-120714D01*
Y-122047D01*
Y-121047D01*
X119095D01*
X-23622Y-229331D02*
Y-227998D01*
X-22956Y-227331D01*
X-22289Y-227998D01*
Y-229331D01*
Y-228331D01*
X-23622D01*
Y-233268D02*
Y-231935D01*
X-22956Y-231268D01*
X-22289Y-231935D01*
Y-233268D01*
Y-232268D01*
X-23622D01*
Y-237205D02*
Y-235872D01*
X-22956Y-235205D01*
X-22289Y-235872D01*
Y-237205D01*
Y-236205D01*
X-23622D01*
Y-241142D02*
Y-239809D01*
X-22956Y-239142D01*
X-22289Y-239809D01*
Y-241142D01*
Y-240142D01*
X-23622D01*
Y-282480D02*
Y-281147D01*
X-22956Y-280481D01*
X-22289Y-281147D01*
Y-282480D01*
Y-281481D01*
X-23622D01*
Y-286417D02*
Y-285084D01*
X-22956Y-284418D01*
X-22289Y-285084D01*
Y-286417D01*
Y-285418D01*
X-23622D01*
Y-290354D02*
Y-289021D01*
X-22956Y-288355D01*
X-22289Y-289021D01*
Y-290354D01*
Y-289355D01*
X-23622D01*
Y-294291D02*
Y-292958D01*
X-22956Y-292292D01*
X-22289Y-292958D01*
Y-294291D01*
Y-293292D01*
X-23622D01*
Y-335630D02*
Y-334297D01*
X-22956Y-333631D01*
X-22289Y-334297D01*
Y-335630D01*
Y-334630D01*
X-23622D01*
Y-339567D02*
Y-338234D01*
X-22956Y-337568D01*
X-22289Y-338234D01*
Y-339567D01*
Y-338567D01*
X-23622D01*
Y-346457D02*
Y-345124D01*
X-22956Y-344457D01*
X-22289Y-345124D01*
Y-346457D01*
Y-345457D01*
X-23622D01*
X107409Y-141732D02*
Y-140399D01*
X108076Y-139733D01*
X108742Y-140399D01*
Y-141732D01*
Y-140733D01*
X107409D01*
X99410Y-141732D02*
Y-140399D01*
X100076Y-139733D01*
X100742Y-140399D01*
Y-141732D01*
Y-140733D01*
X99410D01*
X-23622Y-70866D02*
Y-69533D01*
X-22956Y-68867D01*
X-22289Y-69533D01*
Y-70866D01*
Y-69867D01*
X-23622D01*
Y-66929D02*
Y-65596D01*
X-22956Y-64930D01*
X-22289Y-65596D01*
Y-66929D01*
Y-65929D01*
X-23622D01*
Y-62992D02*
Y-61659D01*
X-22956Y-60993D01*
X-22289Y-61659D01*
Y-62992D01*
Y-61992D01*
X-23622D01*
Y-60039D02*
Y-58706D01*
X-22956Y-58040D01*
X-22289Y-58706D01*
Y-60039D01*
Y-59040D01*
X-23622D01*
Y-102362D02*
Y-101029D01*
X-22956Y-100363D01*
X-22289Y-101029D01*
Y-102362D01*
Y-101363D01*
X-23622D01*
Y-106299D02*
Y-104966D01*
X-22956Y-104300D01*
X-22289Y-104966D01*
Y-106299D01*
Y-105299D01*
X-23622D01*
Y-110236D02*
Y-108903D01*
X-22956Y-108237D01*
X-22289Y-108903D01*
Y-110236D01*
Y-109237D01*
X-23622D01*
Y-114173D02*
Y-112840D01*
X-22956Y-112174D01*
X-22289Y-112840D01*
Y-114173D01*
Y-113174D01*
X-23622D01*
Y-187992D02*
Y-186659D01*
X-22956Y-185993D01*
X-22289Y-186659D01*
Y-187992D01*
Y-186993D01*
X-23622D01*
Y-184055D02*
Y-182722D01*
X-22956Y-182056D01*
X-22289Y-182722D01*
Y-184055D01*
Y-183055D01*
X-23622D01*
Y-181102D02*
Y-179770D01*
X-22956Y-179103D01*
X-22289Y-179770D01*
Y-181102D01*
Y-180103D01*
X-23622D01*
Y-177165D02*
Y-175832D01*
X-22956Y-175166D01*
X-22289Y-175832D01*
Y-177165D01*
Y-176166D01*
X-23622D01*
X117126Y-128047D02*
Y-126714D01*
X117792Y-126047D01*
X118459Y-126714D01*
Y-128047D01*
Y-127047D01*
X117126D01*
Y-124047D02*
Y-122714D01*
X117792Y-122047D01*
X118459Y-122714D01*
Y-124047D01*
Y-123047D01*
X117126D01*
Y-119921D02*
Y-118588D01*
X117792Y-117922D01*
X118459Y-118588D01*
Y-119921D01*
Y-118922D01*
X117126D01*
X101284Y-112205D02*
Y-110872D01*
X101950Y-110205D01*
X102616Y-110872D01*
Y-112205D01*
Y-111205D01*
X101284D01*
X97284Y-112205D02*
Y-110872D01*
X97950Y-110205D01*
X98616Y-110872D01*
Y-112205D01*
Y-111205D01*
X97284D01*
X650745Y-95108D02*
X651545Y-94308D01*
X652345Y-95108D01*
X651545Y-95908D01*
X650745Y-95108D01*
X412556Y7254D02*
X413356Y8054D01*
X414156Y7254D01*
X413356Y6454D01*
X412556Y7254D01*
Y-95108D02*
X413356Y-94308D01*
X414156Y-95108D01*
X413356Y-95908D01*
X412556Y-95108D01*
X650745Y7254D02*
X651545Y8054D01*
X652345Y7254D01*
X651545Y6454D01*
X650745Y7254D01*
X71080Y7412D02*
X71880Y8212D01*
X72680Y7412D01*
X71880Y6612D01*
X71080Y7412D01*
X309269Y-94950D02*
X310069Y-94151D01*
X310869Y-94950D01*
X310069Y-95750D01*
X309269Y-94950D01*
Y7412D02*
X310069Y8212D01*
X310869Y7412D01*
X310069Y6612D01*
X309269Y7412D01*
X71080Y-94950D02*
X71880Y-94151D01*
X72680Y-94950D01*
X71880Y-95750D01*
X71080Y-94950D01*
X98216Y-122453D02*
Y-120853D01*
X99816D01*
Y-122453D01*
X98216D01*
X98616Y-122054D02*
Y-121254D01*
X99416D01*
Y-122054D01*
X98616D01*
X102547Y-122453D02*
Y-120853D01*
X104147D01*
Y-122453D01*
X102547D01*
X102946Y-122054D02*
Y-121254D01*
X103746D01*
Y-122054D01*
X102946D01*
X106877Y-122453D02*
Y-120853D01*
X108477D01*
Y-122453D01*
X106877D01*
X107277Y-122054D02*
Y-121254D01*
X108077D01*
Y-122054D01*
X107277D01*
X98216Y-126784D02*
Y-125184D01*
X99816D01*
Y-126784D01*
X98216D01*
X98616Y-126384D02*
Y-125584D01*
X99416D01*
Y-126384D01*
X98616D01*
X102547Y-126784D02*
Y-125184D01*
X104147D01*
Y-126784D01*
X102547D01*
X102946Y-126384D02*
Y-125584D01*
X103746D01*
Y-126384D01*
X102946D01*
X106877Y-126784D02*
Y-125184D01*
X108477D01*
Y-126784D01*
X106877D01*
X107277Y-126384D02*
Y-125584D01*
X108077D01*
Y-126384D01*
X107277D01*
X98216Y-131115D02*
Y-129515D01*
X99816D01*
Y-131115D01*
X98216D01*
X98616Y-130715D02*
Y-129915D01*
X99416D01*
Y-130715D01*
X98616D01*
X102547Y-131115D02*
Y-129515D01*
X104147D01*
Y-131115D01*
X102547D01*
X102946Y-130715D02*
Y-129915D01*
X103746D01*
Y-130715D01*
X102946D01*
X106877Y-131115D02*
Y-129515D01*
X108477D01*
Y-131115D01*
X106877D01*
X107277Y-130715D02*
Y-129915D01*
X108077D01*
Y-130715D01*
X107277D01*
X544291Y-195718D02*
Y-194385D01*
X544958Y-193719D01*
X545624Y-194385D01*
Y-195718D01*
Y-194718D01*
X544291D01*
X469521Y-137615D02*
Y-136282D01*
X470187Y-135615D01*
X470854Y-136282D01*
Y-137615D01*
Y-136615D01*
X469521D01*
X533878Y-117716D02*
Y-116383D01*
X534545Y-115717D01*
X535211Y-116383D01*
Y-117716D01*
Y-116717D01*
X533878D01*
X524606Y-125836D02*
Y-124503D01*
X525273Y-123837D01*
X525939Y-124503D01*
Y-125836D01*
Y-124837D01*
X524606D01*
X524557Y-128740D02*
Y-127407D01*
X525223Y-126740D01*
X525890Y-127407D01*
Y-128740D01*
Y-127740D01*
X524557D01*
X450850Y-174127D02*
Y-172794D01*
X451516Y-172127D01*
X452182Y-172794D01*
Y-174127D01*
Y-173127D01*
X450850D01*
X512795Y-104214D02*
Y-102881D01*
X513462Y-102215D01*
X514128Y-102881D01*
Y-104214D01*
Y-103215D01*
X512795D01*
X463551Y-116025D02*
Y-114692D01*
X464218Y-114026D01*
X464884Y-114692D01*
Y-116025D01*
Y-115025D01*
X463551D01*
X658465Y-37647D02*
Y-36314D01*
X659131Y-35648D01*
X659797Y-36314D01*
Y-37647D01*
Y-36648D01*
X658465D01*
Y-29773D02*
Y-28440D01*
X659131Y-27774D01*
X659797Y-28440D01*
Y-29773D01*
Y-28774D01*
X658465D01*
X625000Y-21899D02*
Y-20566D01*
X625667Y-19900D01*
X626333Y-20566D01*
Y-21899D01*
Y-20899D01*
X625000D01*
X190354Y-377411D02*
Y-376078D01*
X191021Y-375412D01*
X191687Y-376078D01*
Y-377411D01*
Y-376411D01*
X190354D01*
X314961Y-118947D02*
Y-117614D01*
X315627Y-116947D01*
X316294Y-117614D01*
Y-118947D01*
Y-117947D01*
X314961D01*
X430807Y-175344D02*
Y-174011D01*
X431473Y-173345D01*
X432140Y-174011D01*
Y-175344D01*
Y-174344D01*
X430807D01*
X309016Y-128659D02*
Y-127326D01*
X309682Y-126660D01*
X310349Y-127326D01*
Y-128659D01*
Y-127659D01*
X309016D01*
X418898Y-144143D02*
Y-142810D01*
X419564Y-142144D01*
X420231Y-142810D01*
Y-144143D01*
Y-143144D01*
X418898D01*
X416106Y-144180D02*
Y-142847D01*
X416772Y-142180D01*
X417438Y-142847D01*
Y-144180D01*
Y-143180D01*
X416106D01*
X398568Y-145083D02*
Y-143750D01*
X399235Y-143084D01*
X399901Y-143750D01*
Y-145083D01*
Y-144083D01*
X398568D01*
X210433Y-374655D02*
Y-373322D01*
X211100Y-372656D01*
X211766Y-373322D01*
Y-374655D01*
Y-373655D01*
X210433D01*
X206496Y-374655D02*
Y-373322D01*
X207162Y-372656D01*
X207829Y-373322D01*
Y-374655D01*
Y-373655D01*
X206496D01*
X442126Y-306742D02*
Y-305409D01*
X442792Y-304742D01*
X443459Y-305409D01*
Y-306742D01*
Y-305742D01*
X442126D01*
X439370Y-306742D02*
Y-305409D01*
X440036Y-304742D01*
X440703Y-305409D01*
Y-306742D01*
Y-305742D01*
X439370D01*
X237992Y-374655D02*
Y-373322D01*
X238659Y-372656D01*
X239325Y-373322D01*
Y-374655D01*
Y-373655D01*
X237992D01*
X241929Y-374655D02*
Y-373322D01*
X242596Y-372656D01*
X243262Y-373322D01*
Y-374655D01*
Y-373655D01*
X241929D01*
X253655Y-374421D02*
Y-373088D01*
X254322Y-372422D01*
X254988Y-373088D01*
Y-374421D01*
Y-373421D01*
X253655D01*
X256890Y-374655D02*
Y-373322D01*
X257556Y-372656D01*
X258223Y-373322D01*
Y-374655D01*
Y-373655D01*
X256890D01*
X273425Y-374655D02*
Y-373322D01*
X274092Y-372656D01*
X274758Y-373322D01*
Y-374655D01*
Y-373655D01*
X273425D01*
X269502Y-374291D02*
Y-372958D01*
X270169Y-372292D01*
X270835Y-372958D01*
Y-374291D01*
Y-373291D01*
X269502D01*
X246339Y-386975D02*
Y-385642D01*
X247005Y-384976D01*
X247672Y-385642D01*
Y-386975D01*
Y-385975D01*
X246339D01*
X249410Y-387253D02*
Y-385921D01*
X250076Y-385254D01*
X250742Y-385921D01*
Y-387253D01*
Y-386254D01*
X249410D01*
X232480Y-387253D02*
Y-385921D01*
X233147Y-385254D01*
X233813Y-385921D01*
Y-387253D01*
Y-386254D01*
X232480D01*
X229331Y-387253D02*
Y-385921D01*
X229997Y-385254D01*
X230664Y-385921D01*
Y-387253D01*
Y-386254D01*
X229331D01*
X436221Y-306742D02*
Y-305409D01*
X436887Y-304742D01*
X437553Y-305409D01*
Y-306742D01*
Y-305742D01*
X436221D01*
X212795Y-387253D02*
Y-385921D01*
X213462Y-385254D01*
X214128Y-385921D01*
Y-387253D01*
Y-386254D01*
X212795D01*
X433465Y-306742D02*
Y-305409D01*
X434131Y-304742D01*
X434797Y-305409D01*
Y-306742D01*
Y-305742D01*
X433465D01*
X215945Y-387253D02*
Y-385921D01*
X216611Y-385254D01*
X217278Y-385921D01*
Y-387253D01*
Y-386254D01*
X215945D01*
X262006Y-387255D02*
Y-385922D01*
X262673Y-385256D01*
X263339Y-385922D01*
Y-387255D01*
Y-386256D01*
X262006D01*
X448032Y-306742D02*
Y-305409D01*
X448698Y-304742D01*
X449364Y-305409D01*
Y-306742D01*
Y-305742D01*
X448032D01*
X265158Y-387253D02*
Y-385921D01*
X265824Y-385254D01*
X266490Y-385921D01*
Y-387253D01*
Y-386254D01*
X265158D01*
X445276Y-306742D02*
Y-305409D01*
X445942Y-304742D01*
X446608Y-305409D01*
Y-306742D01*
Y-305742D01*
X445276D01*
X104528Y-92175D02*
Y-90842D01*
X105194Y-90175D01*
X105860Y-90842D01*
Y-92175D01*
Y-91175D01*
X104528D01*
X269685Y-106151D02*
Y-104818D01*
X270352Y-104152D01*
X271018Y-104818D01*
Y-106151D01*
Y-105151D01*
X269685D01*
X131890Y-72687D02*
Y-71354D01*
X132556Y-70687D01*
X133223Y-71354D01*
Y-72687D01*
Y-71687D01*
X131890D01*
X179134Y-386466D02*
Y-385133D01*
X179800Y-384467D01*
X180467Y-385133D01*
Y-386466D01*
Y-385467D01*
X179134D01*
Y-389616D02*
Y-388283D01*
X179800Y-387616D01*
X180467Y-388283D01*
Y-389616D01*
Y-388616D01*
X179134D01*
X178543Y-377411D02*
Y-376078D01*
X179210Y-375412D01*
X179876Y-376078D01*
Y-377411D01*
Y-376411D01*
X178543D01*
X443898Y-175049D02*
Y-173716D01*
X444564Y-173049D01*
X445231Y-173716D01*
Y-175049D01*
Y-174049D01*
X443898D01*
X99410Y-65797D02*
Y-64464D01*
X100076Y-63797D01*
X100742Y-64464D01*
Y-65797D01*
Y-64797D01*
X99410D01*
Y-57923D02*
Y-56590D01*
X100076Y-55923D01*
X100742Y-56590D01*
Y-57923D01*
Y-56923D01*
X99410D01*
X65945Y-65797D02*
Y-64464D01*
X66611Y-63797D01*
X67278Y-64464D01*
Y-65797D01*
Y-64797D01*
X65945D01*
Y-50049D02*
Y-48716D01*
X66611Y-48050D01*
X67278Y-48716D01*
Y-50049D01*
Y-49049D01*
X65945D01*
X78740Y-238041D02*
Y-236708D01*
X79407Y-236042D01*
X80073Y-236708D01*
Y-238041D01*
Y-237041D01*
X78740D01*
X33465Y19833D02*
Y21166D01*
X34131Y21832D01*
X34797Y21166D01*
Y19833D01*
Y20833D01*
X33465D01*
X40354Y19685D02*
Y21018D01*
X41021Y21684D01*
X41687Y21018D01*
Y19685D01*
Y20685D01*
X40354D01*
X47244Y19685D02*
Y21018D01*
X47910Y21684D01*
X48577Y21018D01*
Y19685D01*
Y20685D01*
X47244D01*
X456742Y-116043D02*
Y-114710D01*
X457409Y-114044D01*
X458075Y-114710D01*
Y-116043D01*
Y-115043D01*
X456742D01*
X464328Y-146397D02*
Y-145064D01*
X464995Y-144398D01*
X465661Y-145064D01*
Y-146397D01*
Y-145397D01*
X464328D01*
X469291Y-143848D02*
Y-142515D01*
X469958Y-141849D01*
X470624Y-142515D01*
Y-143848D01*
Y-142848D01*
X469291D01*
X461319Y-143750D02*
Y-142417D01*
X461985Y-141750D01*
X462652Y-142417D01*
Y-143750D01*
Y-142750D01*
X461319D01*
X457283Y-175147D02*
Y-173814D01*
X457950Y-173148D01*
X458616Y-173814D01*
Y-175147D01*
Y-174148D01*
X457283D01*
X469390Y-175147D02*
Y-173814D01*
X470056Y-173148D01*
X470723Y-173814D01*
Y-175147D01*
Y-174148D01*
X469390D01*
X544291Y-215403D02*
Y-214070D01*
X544958Y-213404D01*
X545624Y-214070D01*
Y-215403D01*
Y-214404D01*
X544291D01*
X512402Y-261958D02*
Y-260625D01*
X513068Y-259959D01*
X513734Y-260625D01*
Y-261958D01*
Y-260959D01*
X512402D01*
Y-265108D02*
Y-263775D01*
X513068Y-263108D01*
X513734Y-263775D01*
Y-265108D01*
Y-264108D01*
X512402D01*
X512543Y-268065D02*
Y-266732D01*
X513209Y-266066D01*
X513876Y-266732D01*
Y-268065D01*
Y-267066D01*
X512543D01*
X437697Y-175246D02*
Y-173913D01*
X438363Y-173246D01*
X439030Y-173913D01*
Y-175246D01*
Y-174246D01*
X437697D01*
X433858Y-175246D02*
Y-173913D01*
X434525Y-173246D01*
X435191Y-173913D01*
Y-175246D01*
Y-174246D01*
X433858D01*
X404823Y-175344D02*
Y-174011D01*
X405489Y-173345D01*
X406156Y-174011D01*
Y-175344D01*
Y-174344D01*
X404823D01*
X402264Y-175344D02*
Y-174011D01*
X402930Y-173345D01*
X403597Y-174011D01*
Y-175344D01*
Y-174344D01*
X402264D01*
X309016Y-113986D02*
Y-112653D01*
X309682Y-111986D01*
X310349Y-112653D01*
Y-113986D01*
Y-112986D01*
X309016D01*
X193898Y-115009D02*
Y-113677D01*
X194564Y-113010D01*
X195230Y-113677D01*
Y-115009D01*
Y-114010D01*
X193898D01*
Y-119931D02*
Y-118598D01*
X194564Y-117931D01*
X195230Y-118598D01*
Y-119931D01*
Y-118931D01*
X193898D01*
X309055Y-123868D02*
Y-122535D01*
X309722Y-121868D01*
X310388Y-122535D01*
Y-123868D01*
Y-122868D01*
X309055D01*
X182677Y-386466D02*
Y-385133D01*
X183344Y-384467D01*
X184010Y-385133D01*
Y-386466D01*
Y-385467D01*
X182677D01*
X186614Y-386466D02*
Y-385133D01*
X187281Y-384467D01*
X187947Y-385133D01*
Y-386466D01*
Y-385467D01*
X186614D01*
X182677Y-389616D02*
Y-388283D01*
X183344Y-387616D01*
X184010Y-388283D01*
Y-389616D01*
Y-388616D01*
X182677D01*
X186614Y-389616D02*
Y-388283D01*
X187281Y-387616D01*
X187947Y-388283D01*
Y-389616D01*
Y-388616D01*
X186614D01*
D261*
X673201Y-135695D02*
G03*
X673201Y-135695I-800J0D01*
G01*
X685839Y-340551D02*
G03*
X685839Y-340551I-800J0D01*
G01*
X685839Y0D02*
G03*
X685839Y0I-800J0D01*
G01*
X487020Y-340551D02*
G03*
X487020Y-340551I-800J0D01*
G01*
D262*
X685439Y-340551D02*
G03*
X685439Y-340551I-400J0D01*
G01*
X685439Y0D02*
G03*
X685439Y0I-400J0D01*
G01*
X486621Y-340551D02*
G03*
X486621Y-340551I-400J0D01*
G01*
M02*
